%FSTAX25Y25*%
%MOIN*%
%SFA1B1*%

%IPPOS*%
%AMD54*
4,1,8,0.010500,-0.010000,0.010500,0.010000,0.000000,0.020400,0.000000,0.020400,-0.010500,0.010000,-0.010500,-0.010000,0.000000,-0.020400,0.000000,-0.020400,0.010500,-0.010000,0.0*
1,1,0.020960,0.000000,-0.010000*
1,1,0.020960,0.000000,0.010000*
1,1,0.020960,0.000000,0.010000*
1,1,0.020960,0.000000,-0.010000*
%
%ADD22R,0.041340X0.043310*%
%ADD23R,0.039370X0.027560*%
%ADD24R,0.055120X0.055120*%
%ADD25R,0.039370X0.055120*%
%ADD26R,0.086610X0.041340*%
%ADD27R,0.041340X0.039370*%
%ADD28R,0.035430X0.019680*%
%ADD29R,0.077560X0.022440*%
%ADD30R,0.041340X0.025590*%
%ADD31R,0.050000X0.200000*%
%ADD32R,0.070870X0.009840*%
%ADD33R,0.057090X0.037400*%
%ADD34R,0.037400X0.031500*%
%ADD35R,0.037400X0.037400*%
%ADD36R,0.029530X0.033470*%
%ADD37R,0.035430X0.027560*%
%ADD38R,0.023620X0.031500*%
%ADD39R,0.039370X0.028350*%
%ADD40R,0.023620X0.025590*%
%ADD41R,0.028000X0.165000*%
%ADD42R,0.028000X0.126000*%
%ADD43O,0.086610X0.023620*%
%ADD44O,0.074800X0.023620*%
%ADD45R,0.212600X0.114170*%
%ADD46R,0.082870X0.044090*%
%ADD47R,0.009840X0.061020*%
%ADD48R,0.066930X0.053150*%
%ADD49R,0.053150X0.066930*%
%ADD50R,0.061020X0.009840*%
%ADD51R,0.026570X0.009840*%
%ADD52R,0.009840X0.026570*%
%ADD53R,0.019680X0.013780*%
G04~CAMADD=54~8~0.0~0.0~408.8~209.5~104.8~0.0~15~0.0~0.0~0.0~0.0~0~0.0~0.0~0.0~0.0~0~0.0~0.0~0.0~270.0~210.0~409.0*
%ADD54D54*%
%ADD55R,0.020950X0.040880*%
%ADD56R,0.033470X0.039370*%
%ADD57R,0.045280X0.057090*%
%ADD58R,0.037400X0.033470*%
%ADD59R,0.043310X0.041340*%
%ADD60R,0.037400X0.039370*%
%ADD61R,0.057090X0.045280*%
%ADD62R,0.028350X0.039370*%
%LNtimecard-dc-beta-v1-1*%
%LPD*%
G36*
X0679191Y0117695D02*
X0679732D01*
Y0117641*
X0680002*
Y0117587*
X0680219*
Y0117533*
X0680327*
Y0117479*
X0680489*
Y0117425*
X0680597*
Y0117371*
X0680759*
Y0117317*
X0680813*
Y0117263*
X0680922*
Y0117209*
X068103*
Y0117155*
X0681084*
Y0117101*
X0681192*
Y0117047*
X0681246*
Y0116993*
X0681354*
Y0116939*
X0681408*
Y0116885*
X0681462*
Y0116831*
X0681516*
Y0116776*
X068157*
Y0116722*
X0681624*
Y0116668*
X0681678*
Y0116614*
X0681732*
Y011656*
X0681786*
Y0116506*
X0681841*
Y0116452*
X0681895*
Y0116398*
X0681949*
Y0116344*
Y011629*
X0682003*
Y0116236*
X0682057*
Y0116182*
Y0116128*
X0682111*
Y0116074*
X0682165*
Y011602*
Y0115965*
X0682219*
Y0115911*
Y0115857*
X0682273*
Y0115803*
X0682327*
Y0115749*
Y0115695*
X0682381*
Y0115641*
Y0115587*
Y0115533*
X0682435*
Y0115479*
Y0115425*
X0682489*
Y0115371*
Y0115317*
Y0115263*
X0682543*
Y0115209*
Y0115155*
Y0115101*
Y0115047*
X0682597*
Y0114992*
Y0114938*
Y0114884*
Y011483*
X0682652*
Y0114776*
Y0114722*
Y0114668*
Y0114614*
Y011456*
Y0114506*
Y0114452*
Y0114398*
Y0114344*
Y011429*
X0682705*
Y0114235*
Y0114181*
Y0114127*
Y0114073*
X0682652*
Y0114019*
Y0113965*
Y0113911*
Y0113857*
Y0113803*
Y0113749*
Y0113695*
Y0113641*
Y0113587*
X0682597*
Y0113533*
Y0113479*
Y0113425*
Y0113371*
Y0113317*
X0682543*
Y0113262*
Y0113208*
Y0113154*
X0682489*
Y01131*
Y0113046*
Y0112992*
X0682435*
Y0112938*
Y0112884*
Y011283*
X0682381*
Y0112776*
Y0112722*
X0682327*
Y0112668*
Y0112614*
X0682273*
Y011256*
Y0112505*
X0682219*
Y0112452*
Y0112397*
X0682165*
Y0112343*
Y0112289*
X0682111*
Y0112235*
X0682057*
Y0112181*
Y0112127*
X0682003*
Y0112073*
X0681949*
Y0112019*
X0681895*
Y0111965*
Y0111911*
X0681841*
Y0111857*
X0681786*
Y0111803*
X0681732*
Y0111749*
X0681678*
Y0111695*
X0681624*
Y0111641*
X068157*
Y0111586*
X0681516*
Y0111532*
X0681462*
Y0111478*
X0681354*
Y0111424*
X06813*
Y011137*
X0681246*
Y0111316*
X0681192*
Y0111262*
X0681084*
Y0111208*
X068103*
Y0111154*
X0680922*
Y01111*
X0680813*
Y0111046*
X0680705*
Y0110992*
X0680597*
Y0110938*
X0680489*
Y0110884*
X0680327*
Y011083*
X0680165*
Y0110776*
X0679948*
Y0110722*
X0679678*
Y0110668*
X0674434*
Y0110722*
X0674164*
Y0110776*
X0674002*
Y011083*
X0673839*
Y0110884*
X0673677*
Y0110938*
X0673569*
Y0110992*
X0673407*
Y0111046*
X0673353*
Y01111*
X0673245*
Y0111154*
X0673137*
Y0111208*
X0673082*
Y0111262*
X0672974*
Y0111316*
X067292*
Y011137*
X0672812*
Y0111424*
X0672758*
Y0111478*
X0672704*
Y0111532*
X067265*
Y0111586*
X0672596*
Y0111641*
X0672542*
Y0111695*
X0672488*
Y0111749*
X0672434*
Y0111803*
X067238*
Y0111857*
X0672326*
Y0111911*
X0672272*
Y0111965*
X0672218*
Y0112019*
Y0112073*
X0672163*
Y0112127*
X0672109*
Y0112181*
X0672055*
Y0112235*
Y0112289*
X0672001*
Y0112343*
Y0112397*
X0671947*
Y0112452*
X0671893*
Y0112505*
Y011256*
X0671839*
Y0112614*
Y0112668*
X0671785*
Y0112722*
Y0112776*
X0671731*
Y011283*
Y0112884*
Y0112938*
X0671677*
Y0112992*
Y0113046*
Y01131*
X0671623*
Y0113154*
Y0113208*
Y0113262*
X0671569*
Y0113317*
Y0113371*
Y0113425*
Y0113479*
Y0113533*
X0671515*
Y0113587*
Y0113641*
Y0113695*
Y0113749*
Y0113803*
X0671461*
Y0113857*
Y0113911*
Y0113965*
Y0114019*
Y0114073*
Y0114127*
Y0114181*
Y0114235*
Y011429*
Y0114344*
Y0114398*
Y0114452*
Y0114506*
X0671515*
Y011456*
Y0114614*
Y0114668*
Y0114722*
Y0114776*
Y011483*
Y0114884*
X0671569*
Y0114938*
Y0114992*
Y0115047*
Y0115101*
X0671623*
Y0115155*
Y0115209*
Y0115263*
Y0115317*
X0671677*
Y0115371*
Y0115425*
X0671731*
Y0115479*
Y0115533*
Y0115587*
X0671785*
Y0115641*
Y0115695*
X0671839*
Y0115749*
Y0115803*
X0671893*
Y0115857*
Y0115911*
X0671947*
Y0115965*
Y011602*
X0672001*
Y0116074*
X0672055*
Y0116128*
Y0116182*
X0672109*
Y0116236*
X0672163*
Y011629*
Y0116344*
X0672218*
Y0116398*
X0672272*
Y0116452*
X0672326*
Y0116506*
X067238*
Y011656*
X0672434*
Y0116614*
X0672488*
Y0116668*
X0672542*
Y0116722*
X0672596*
Y0116776*
X067265*
Y0116831*
X0672704*
Y0116885*
X0672758*
Y0116939*
X0672812*
Y0116993*
X0672866*
Y0117047*
X0672974*
Y0117101*
X0673028*
Y0117155*
X0673137*
Y0117209*
X0673191*
Y0117263*
X0673299*
Y0117317*
X0673407*
Y0117371*
X0673515*
Y0117425*
X0673677*
Y0117479*
X0673785*
Y0117533*
X0673947*
Y0117587*
X0674164*
Y0117641*
X067438*
Y0117695*
X0674975*
Y011775*
X0679083*
Y0117695*
X0679137*
Y011775*
X0679191*
Y0117695*
G37*
G36*
X0597288Y0095098D02*
X0597504D01*
Y0095043*
X0597666*
Y009499*
X0597774*
Y0094935*
X0597882*
Y0094881*
X0597936*
Y0094827*
X0598044*
Y0094773*
X0598099*
Y0094719*
X0598207*
Y0094665*
X0598261*
Y0094611*
X0598315*
Y0094557*
X0598369*
Y0094503*
X0598423*
Y0094449*
X0598477*
Y0094395*
Y0094341*
X0598531*
Y0094287*
X0598585*
Y0094233*
Y0094178*
X0598639*
Y0094125*
X0598693*
Y009407*
Y0094016*
X0598747*
Y0093962*
Y0093908*
Y0093854*
X0598801*
Y00938*
Y0093746*
Y0093692*
X0598855*
Y0093638*
Y0093584*
Y009353*
Y0093476*
X0598909*
Y0093422*
Y0093368*
Y0093313*
Y009326*
Y0093205*
Y0093151*
Y0093097*
Y0093043*
Y0092989*
Y0092935*
Y0092881*
Y0092827*
Y0092773*
X0598855*
Y0092719*
Y0092665*
Y0092611*
Y0092557*
X0598801*
Y0092503*
Y0092449*
Y0092395*
X0598747*
Y009234*
Y0092286*
X0598693*
Y0092232*
Y0092178*
X0598639*
Y0092124*
Y009207*
X0598585*
Y0092016*
X0598531*
Y0091962*
Y0091908*
X0598477*
Y0091854*
X0598423*
Y00918*
X0598369*
Y0091746*
X0598315*
Y0091692*
X0598261*
Y0091638*
X0598207*
Y0091584*
X0598152*
Y009153*
X0598099*
Y0091475*
X059799*
Y0091421*
X0597936*
Y0091367*
X0597828*
Y0091313*
X059772*
Y0091259*
X0597558*
Y0091205*
X0597396*
Y0091151*
X0597071*
Y0091097*
X0596693*
Y0091151*
X0596369*
Y0091205*
X0596206*
Y0091259*
X0596098*
Y0091313*
X0595936*
Y0091367*
X0595882*
Y0091421*
X0595774*
Y0091475*
X059572*
Y009153*
X0595612*
Y0091584*
X0595558*
Y0091638*
X0595504*
Y0091692*
X0595449*
Y0091746*
X0595395*
Y00918*
X0595341*
Y0091854*
X0595287*
Y0091908*
X0595233*
Y0091962*
Y0092016*
X0595179*
Y009207*
Y0092124*
X0595125*
Y0092178*
X0595071*
Y0092232*
Y0092286*
X0595017*
Y009234*
Y0092395*
Y0092449*
X0594963*
Y0092503*
Y0092557*
Y0092611*
X0594909*
Y0092665*
Y0092719*
Y0092773*
Y0092827*
Y0092881*
X0594855*
Y0092935*
Y0092989*
Y0093043*
Y0093097*
Y0093151*
Y0093205*
Y009326*
Y0093313*
Y0093368*
Y0093422*
X0594909*
Y0093476*
Y009353*
Y0093584*
Y0093638*
Y0093692*
X0594963*
Y0093746*
Y00938*
Y0093854*
X0595017*
Y0093908*
Y0093962*
X0595071*
Y0094016*
Y009407*
X0595125*
Y0094125*
Y0094178*
X0595179*
Y0094233*
Y0094287*
X0595233*
Y0094341*
X0595287*
Y0094395*
X0595341*
Y0094449*
Y0094503*
X0595395*
Y0094557*
X0595449*
Y0094611*
X0595504*
Y0094665*
X0595612*
Y0094719*
X0595666*
Y0094773*
X059572*
Y0094827*
X0595828*
Y0094881*
X0595882*
Y0094935*
X059599*
Y009499*
X0596152*
Y0095043*
X059626*
Y0095098*
X0596477*
Y0095152*
X0597288*
Y0095098*
G37*
G36*
X0597233Y0087799D02*
X059745D01*
Y0087745*
X0597612*
Y0087691*
X059772*
Y0087637*
X0597828*
Y0087583*
X0597936*
Y0087529*
X0598044*
Y0087475*
X0598099*
Y0087421*
X0598152*
Y0087367*
X0598261*
Y0087313*
X0598315*
Y0087259*
X0598369*
Y0087204*
X0598423*
Y0087151*
Y0087096*
X0598477*
Y0087042*
X0598531*
Y0086988*
X0598585*
Y0086934*
Y008688*
X0598639*
Y0086826*
Y0086772*
X0598693*
Y0086718*
Y0086664*
X0598747*
Y008661*
Y0086556*
X0598801*
Y0086502*
Y0086448*
Y0086394*
X0598855*
Y0086339*
Y0086286*
Y0086231*
Y0086177*
X0598909*
Y0086123*
Y0086069*
Y0086015*
Y0085961*
Y0085907*
Y0085853*
Y0085799*
Y0085745*
Y0085691*
Y0085637*
Y0085583*
Y0085529*
Y0085474*
X0598855*
Y0085421*
Y0085366*
Y0085312*
Y0085258*
X0598801*
Y0085204*
Y008515*
Y0085096*
X0598747*
Y0085042*
Y0084988*
X0598693*
Y0084934*
Y008488*
X0598639*
Y0084826*
Y0084772*
X0598585*
Y0084718*
Y0084664*
X0598531*
Y008461*
X0598477*
Y0084556*
X0598423*
Y0084501*
Y0084447*
X0598369*
Y0084393*
X0598315*
Y0084339*
X0598207*
Y0084285*
X0598152*
Y0084231*
X0598099*
Y0084177*
X0598044*
Y0084123*
X0597936*
Y0084069*
X0597828*
Y0084015*
X059772*
Y0083961*
X0597612*
Y0083907*
X059745*
Y0083853*
X0597179*
Y0083799*
X0596585*
Y0083853*
X0596314*
Y0083907*
X0596152*
Y0083961*
X0596044*
Y0084015*
X0595936*
Y0084069*
X0595828*
Y0084123*
X0595774*
Y0084177*
X0595666*
Y0084231*
X0595612*
Y0084285*
X0595558*
Y0084339*
X0595504*
Y0084393*
X0595449*
Y0084447*
X0595395*
Y0084501*
X0595341*
Y0084556*
X0595287*
Y008461*
X0595233*
Y0084664*
Y0084718*
X0595179*
Y0084772*
X0595125*
Y0084826*
Y008488*
X0595071*
Y0084934*
Y0084988*
X0595017*
Y0085042*
Y0085096*
Y008515*
X0594963*
Y0085204*
Y0085258*
Y0085312*
X0594909*
Y0085366*
Y0085421*
Y0085474*
Y0085529*
X0594855*
Y0085583*
Y0085637*
Y0085691*
Y0085745*
Y0085799*
Y0085853*
Y0085907*
Y0085961*
Y0086015*
Y0086069*
Y0086123*
X0594909*
Y0086177*
Y0086231*
Y0086286*
Y0086339*
X0594963*
Y0086394*
Y0086448*
Y0086502*
Y0086556*
X0595017*
Y008661*
Y0086664*
X0595071*
Y0086718*
Y0086772*
X0595125*
Y0086826*
Y008688*
X0595179*
Y0086934*
X0595233*
Y0086988*
Y0087042*
X0595287*
Y0087096*
X0595341*
Y0087151*
X0595395*
Y0087204*
X0595449*
Y0087259*
X0595504*
Y0087313*
X0595558*
Y0087367*
X0595612*
Y0087421*
X0595666*
Y0087475*
X0595774*
Y0087529*
X0595828*
Y0087583*
X0595936*
Y0087637*
X0596044*
Y0087691*
X0596152*
Y0087745*
X0596314*
Y0087799*
X0596585*
Y0087853*
X0597233*
Y0087799*
G37*
G36*
X0691626Y0089475D02*
X069195D01*
Y0089421*
X0692166*
Y0089367*
X0692329*
Y0089313*
X0692491*
Y0089259*
X0692599*
Y0089205*
X0692761*
Y0089151*
X0692869*
Y0089097*
X0692923*
Y0089043*
X0693031*
Y0088989*
X069314*
Y0088934*
X0693194*
Y008888*
X0693302*
Y0088826*
X0693356*
Y0088772*
X069341*
Y0088718*
X0693464*
Y0088664*
X0693572*
Y008861*
X0693626*
Y0088556*
X069368*
Y0088502*
X0693734*
Y0088448*
X0693788*
Y0088394*
X0693842*
Y008834*
X0693896*
Y0088286*
X069395*
Y0088232*
Y0088178*
X0694004*
Y0088124*
X0694059*
Y0088069*
X0694113*
Y0088016*
Y0087961*
X0694167*
Y0087907*
X0694221*
Y0087853*
Y0087799*
X0694275*
Y0087745*
Y0087691*
X0694329*
Y0087637*
X0694383*
Y0087583*
Y0087529*
X0694437*
Y0087475*
Y0087421*
Y0087367*
X0694491*
Y0087313*
Y0087259*
X0694545*
Y0087204*
Y0087151*
Y0087096*
X0694599*
Y0087042*
Y0086988*
Y0086934*
X0694653*
Y008688*
Y0086826*
Y0086772*
Y0086718*
X0694707*
Y0086664*
Y008661*
Y0086556*
Y0086502*
Y0086448*
Y0086394*
X0694761*
Y0086339*
Y0086286*
Y0086231*
Y0086177*
Y0086123*
Y0086069*
Y0086015*
Y0085961*
Y0085907*
Y0085853*
Y0085799*
Y0085745*
Y0085691*
Y0085637*
Y0085583*
X0694707*
Y0085529*
Y0085474*
Y0085421*
Y0085366*
Y0085312*
Y0085258*
X0694653*
Y0085204*
Y008515*
Y0085096*
Y0085042*
X0694599*
Y0084988*
Y0084934*
Y008488*
X0694545*
Y0084826*
Y0084772*
Y0084718*
X0694491*
Y0084664*
Y008461*
X0694437*
Y0084556*
Y0084501*
X0694383*
Y0084447*
Y0084393*
X0694329*
Y0084339*
Y0084285*
X0694275*
Y0084231*
Y0084177*
X0694221*
Y0084123*
X0694167*
Y0084069*
Y0084015*
X0694113*
Y0083961*
X0694059*
Y0083907*
Y0083853*
X0694004*
Y0083799*
X069395*
Y0083745*
X0693896*
Y0083691*
X0693842*
Y0083636*
X0693788*
Y0083582*
X0693734*
Y0083528*
X069368*
Y0083474*
X0693626*
Y008342*
X0693572*
Y0083366*
X0693518*
Y0083312*
X0693464*
Y0083258*
X069341*
Y0083204*
X0693302*
Y008315*
X0693248*
Y0083096*
X0693194*
Y0083042*
X0693085*
Y0082988*
X0692977*
Y0082934*
X0692923*
Y008288*
X0692815*
Y0082825*
X0692707*
Y0082771*
X0692545*
Y0082717*
X0692437*
Y0082663*
X0692275*
Y0082609*
X0692058*
Y0082555*
X0691788*
Y0082501*
X0691464*
Y0082447*
X0691409*
Y0082501*
X0691356*
Y0082447*
X0691301*
Y0082501*
X0691247*
Y0082447*
X0690869*
Y0082501*
X069049*
Y0082555*
X069022*
Y0082609*
X0690058*
Y0082663*
X0689896*
Y0082717*
X0689734*
Y0082771*
X0689626*
Y0082825*
X0689517*
Y008288*
X0689409*
Y0082934*
X0689301*
Y0082988*
X0689247*
Y0083042*
X0689139*
Y0083096*
X0689085*
Y008315*
X0688977*
Y0083204*
X0688923*
Y0083258*
X0688869*
Y0083312*
X0688814*
Y0083366*
X0688706*
Y008342*
X0688652*
Y0083474*
X0688598*
Y0083528*
X0688544*
Y0083582*
X068849*
Y0083636*
X0688436*
Y0083691*
Y0083745*
X0688382*
Y0083799*
X0688328*
Y0083853*
X0688274*
Y0083907*
X068822*
Y0083961*
Y0084015*
X0688166*
Y0084069*
X0688112*
Y0084123*
Y0084177*
X0688058*
Y0084231*
Y0084285*
X0688004*
Y0084339*
X068795*
Y0084393*
Y0084447*
X0687895*
Y0084501*
Y0084556*
X0687841*
Y008461*
Y0084664*
Y0084718*
X0687787*
Y0084772*
Y0084826*
X0687733*
Y008488*
Y0084934*
Y0084988*
X0687679*
Y0085042*
Y0085096*
Y008515*
Y0085204*
X0687625*
Y0085258*
Y0085312*
Y0085366*
Y0085421*
Y0085474*
X0687571*
Y0085529*
Y0085583*
Y0085637*
Y0085691*
Y0085745*
Y0085799*
Y0085853*
Y0085907*
Y0085961*
Y0086015*
Y0086069*
Y0086123*
Y0086177*
Y0086231*
Y0086286*
Y0086339*
Y0086394*
Y0086448*
Y0086502*
X0687625*
Y0086556*
Y008661*
Y0086664*
Y0086718*
Y0086772*
X0687679*
Y0086826*
Y008688*
Y0086934*
Y0086988*
X0687733*
Y0087042*
Y0087096*
Y0087151*
X0687787*
Y0087204*
Y0087259*
Y0087313*
X0687841*
Y0087367*
Y0087421*
X0687895*
Y0087475*
Y0087529*
X068795*
Y0087583*
Y0087637*
X0688004*
Y0087691*
Y0087745*
X0688058*
Y0087799*
Y0087853*
X0688112*
Y0087907*
X0688166*
Y0087961*
Y0088016*
X068822*
Y0088069*
X0688274*
Y0088124*
X0688328*
Y0088178*
Y0088232*
X0688382*
Y0088286*
X0688436*
Y008834*
X068849*
Y0088394*
X0688544*
Y0088448*
X0688598*
Y0088502*
X0688652*
Y0088556*
X0688706*
Y008861*
X0688761*
Y0088664*
X0688814*
Y0088718*
X0688869*
Y0088772*
X0688977*
Y0088826*
X0689031*
Y008888*
X0689139*
Y0088934*
X0689193*
Y0088989*
X0689301*
Y0089043*
X0689355*
Y0089097*
X0689463*
Y0089151*
X0689571*
Y0089205*
X0689679*
Y0089259*
X0689842*
Y0089313*
X0690004*
Y0089367*
X0690166*
Y0089421*
X0690382*
Y0089475*
X0690653*
Y0089529*
X0691626*
Y0089475*
G37*
G36*
X0662919Y0117695D02*
X0663514D01*
Y0117641*
X066373*
Y0117587*
X0663946*
Y0117533*
X0664108*
Y0117479*
X066427*
Y0117425*
X0664378*
Y0117371*
X0664487*
Y0117317*
X0664595*
Y0117263*
X0664703*
Y0117209*
X0664811*
Y0117155*
X0664865*
Y0117101*
X0664973*
Y0117047*
X0665027*
Y0116993*
X0665081*
Y0116939*
X0665189*
Y0116885*
X0665243*
Y0116831*
X0665298*
Y0116776*
X0665352*
Y0116722*
X0665406*
Y0116668*
X066546*
Y0116614*
X0665514*
Y011656*
X0665568*
Y0116506*
X0665622*
Y0116452*
X0665676*
Y0116398*
X066573*
Y0116344*
Y011629*
X0665784*
Y0116236*
X0665838*
Y0116182*
X0665892*
Y0116128*
Y0116074*
X0665946*
Y011602*
Y0115965*
X0666*
Y0115911*
X0666054*
Y0115857*
Y0115803*
X0666109*
Y0115749*
Y0115695*
X0666163*
Y0115641*
Y0115587*
X0666217*
Y0115533*
Y0115479*
Y0115425*
X0666271*
Y0115371*
Y0115317*
Y0115263*
X0666325*
Y0115209*
Y0115155*
Y0115101*
X0666379*
Y0115047*
Y0114992*
Y0114938*
Y0114884*
X0666433*
Y011483*
Y0114776*
Y0114722*
Y0114668*
Y0114614*
Y011456*
X0666487*
Y0114506*
Y0114452*
Y0114398*
Y0114344*
Y011429*
Y0114235*
Y0114181*
Y0114127*
Y0114073*
Y0114019*
Y0113965*
X0666433*
Y0113911*
X0666487*
Y0113857*
X0666433*
Y0113803*
Y0113749*
Y0113695*
Y0113641*
Y0113587*
Y0113533*
Y0113479*
X0666379*
Y0113425*
Y0113371*
Y0113317*
Y0113262*
X0666325*
Y0113208*
Y0113154*
Y01131*
X0666271*
Y0113046*
Y0112992*
Y0112938*
X0666217*
Y0112884*
Y011283*
Y0112776*
X0666163*
Y0112722*
Y0112668*
X0666109*
Y0112614*
Y011256*
X0666054*
Y0112505*
Y0112452*
X0666*
Y0112397*
X0665946*
Y0112343*
Y0112289*
X0665892*
Y0112235*
X0665838*
Y0112181*
Y0112127*
X0665784*
Y0112073*
X066573*
Y0112019*
X0665676*
Y0111965*
Y0111911*
X0665622*
Y0111857*
X0665568*
Y0111803*
X0665514*
Y0111749*
X066546*
Y0111695*
X0665406*
Y0111641*
X0665352*
Y0111586*
X0665298*
Y0111532*
X0665243*
Y0111478*
X0665135*
Y0111424*
X0665081*
Y011137*
X0665027*
Y0111316*
X0664919*
Y0111262*
X0664865*
Y0111208*
X0664757*
Y0111154*
X0664703*
Y01111*
X0664595*
Y0111046*
X0664487*
Y0110992*
X0664378*
Y0110938*
X0664216*
Y0110884*
X0664108*
Y011083*
X0663892*
Y0110776*
X066373*
Y0110722*
X0663405*
Y0110668*
X0655242*
Y0110613*
X065481*
Y0110559*
X0654593*
Y0110505*
X0654377*
Y0110451*
X0654269*
Y0110397*
X0654107*
Y0110343*
X0653999*
Y0110289*
X0653891*
Y0110235*
X0653782*
Y0110181*
X0653674*
Y0110127*
X065362*
Y0110073*
X0653512*
Y0110019*
X0653404*
Y0109965*
X065335*
Y0109911*
X0653296*
Y0109856*
X0653242*
Y0109802*
X0653134*
Y0109748*
X065308*
Y0109694*
X0653025*
Y010964*
X0652971*
Y0109586*
X0652917*
Y0109532*
X0652863*
Y0109478*
X0652809*
Y0109424*
X0652755*
Y010937*
Y0109316*
X0652701*
Y0109262*
X0652647*
Y0109208*
X0652593*
Y0109154*
Y01091*
X0652539*
Y0109046*
X0652485*
Y0108992*
Y0108938*
X0652431*
Y0108883*
X0652377*
Y0108829*
Y0108775*
X0652323*
Y0108721*
Y0108667*
X0652269*
Y0108613*
Y0108559*
X0652214*
Y0108505*
Y0108451*
Y0108397*
X0652161*
Y0108343*
Y0108289*
X0652106*
Y0108235*
Y0108181*
Y0108126*
X0652052*
Y0108072*
Y0108018*
Y0107964*
Y010791*
X0651998*
Y0107856*
Y0107802*
Y0107748*
Y0107694*
Y010764*
Y0107586*
X0651944*
Y0107532*
Y0107478*
Y0107424*
Y010737*
Y0107316*
Y0107262*
Y0107208*
Y0107153*
Y0107099*
Y0107045*
Y0106991*
Y0106937*
Y0106883*
Y0106829*
Y0106775*
Y0106721*
X0651998*
Y0106667*
Y0106613*
Y0106559*
Y0106505*
Y0106451*
Y0106397*
X0652052*
Y0106342*
Y0106288*
Y0106234*
Y010618*
X0652106*
Y0106126*
Y0106072*
Y0106018*
X0652161*
Y0105964*
Y010591*
Y0105856*
X0652214*
Y0105802*
Y0105748*
X0652269*
Y0105694*
Y010564*
X0652323*
Y0105586*
Y0105532*
X0652377*
Y0105477*
Y0105423*
X0652431*
Y0105369*
Y0105315*
X0652485*
Y0105261*
X0652539*
Y0105207*
Y0105153*
X0652593*
Y0105099*
X0652647*
Y0105045*
Y0104991*
X0652701*
Y0104937*
X0652755*
Y0104883*
X0652809*
Y0104829*
X0652863*
Y0104775*
X0652917*
Y0104721*
X0652971*
Y0104667*
X0653025*
Y0104613*
X065308*
Y0104558*
X0653134*
Y0104504*
X0653188*
Y010445*
X0653242*
Y0104396*
X0653296*
Y0104342*
X0653404*
Y0104288*
X0653458*
Y0104234*
X0653566*
Y010418*
X065362*
Y0104126*
X0653728*
Y0104072*
X0653836*
Y0104018*
X0653944*
Y0103964*
X0654053*
Y010391*
X0654161*
Y0103856*
X0654323*
Y0103802*
X0654485*
Y0103747*
X0654701*
Y0103693*
X0654972*
Y0103639*
X0697735*
Y0103585*
X0697789*
Y0103639*
X0697843*
Y0103585*
X0698221*
Y0103531*
X0698438*
Y0103477*
X06986*
Y0103423*
X0698762*
Y0103369*
X0698924*
Y0103315*
X0699032*
Y0103261*
X069914*
Y0103207*
X0699249*
Y0103153*
X0699357*
Y0103099*
X0699411*
Y0103045*
X0699519*
Y0102991*
X0699573*
Y0102937*
X0699681*
Y0102883*
X0699735*
Y0102828*
X0699789*
Y0102774*
X0699843*
Y010272*
X0699951*
Y0102666*
X0700005*
Y0102612*
X0700059*
Y0102558*
X0700113*
Y0102504*
X0700168*
Y010245*
X0700222*
Y0102396*
Y0102342*
X0700276*
Y0102288*
X070033*
Y0102234*
X0700384*
Y010218*
X0700438*
Y0102126*
Y0102072*
X0700492*
Y0102017*
X0700546*
Y0101963*
Y0101909*
X07006*
Y0101855*
X0700654*
Y0101801*
Y0101747*
X0700708*
Y0101693*
Y0101639*
X0700762*
Y0101585*
Y0101531*
X0700816*
Y0101477*
Y0101423*
Y0101369*
X070087*
Y0101315*
Y0101261*
X0700924*
Y0101207*
Y0101153*
Y0101099*
X0700979*
Y0101044*
Y010099*
Y0100936*
Y0100882*
X0701032*
Y0100828*
Y0100774*
Y010072*
Y0100666*
Y0100612*
X0701087*
Y0100558*
Y0100504*
Y010045*
Y0100396*
Y0100342*
Y0100287*
Y0100233*
Y0100179*
Y0100125*
Y0100071*
Y0100017*
Y0099963*
Y0099909*
Y0099855*
Y0099801*
Y0099747*
Y0099693*
Y0099639*
Y0099585*
X0701032*
Y0099531*
Y0099477*
Y0099423*
Y0099369*
Y0099314*
X0700979*
Y009926*
Y0099206*
Y0099152*
Y0099098*
X0700924*
Y0099044*
Y009899*
Y0098936*
X070087*
Y0098882*
Y0098828*
Y0098774*
X0700816*
Y009872*
Y0098666*
X0700762*
Y0098612*
Y0098558*
X0700708*
Y0098504*
Y0098449*
X0700654*
Y0098395*
Y0098341*
X07006*
Y0098287*
Y0098233*
X0700546*
Y0098179*
X0700492*
Y0098125*
Y0098071*
X0700438*
Y0098017*
X0700384*
Y0097963*
X070033*
Y0097909*
X0700276*
Y0097855*
Y0097801*
X0700222*
Y0097747*
X0700168*
Y0097693*
X0700113*
Y0097638*
X0700059*
Y0097584*
X0700005*
Y009753*
X0699951*
Y0097476*
X0699897*
Y0097422*
X0699843*
Y0097368*
X0699735*
Y0097314*
X0699681*
Y009726*
X0699627*
Y0097206*
X0699519*
Y0097152*
X0699465*
Y0097098*
X0699357*
Y0097044*
X0699249*
Y009699*
X0699194*
Y0096936*
X0699032*
Y0096882*
X0698924*
Y0096828*
X0698816*
Y0096773*
X0698654*
Y0096719*
X0698492*
Y0096665*
X0698275*
Y0096611*
X0697951*
Y0096557*
X0669893*
Y0096503*
X0669568*
Y0096449*
X0669352*
Y0096395*
X0669136*
Y0096341*
X0669028*
Y0096287*
X0668866*
Y0096233*
X0668757*
Y0096179*
X0668649*
Y0096125*
X0668541*
Y0096071*
X0668433*
Y0096017*
X0668379*
Y0095963*
X0668271*
Y0095908*
X0668217*
Y0095854*
X0668163*
Y00958*
X0668055*
Y0095746*
X0668001*
Y0095692*
X0667947*
Y0095638*
X0667893*
Y0095584*
X0667838*
Y009553*
X0667784*
Y0095476*
X066773*
Y0095422*
X0667676*
Y0095368*
X0667622*
Y0095314*
X0667568*
Y009526*
X0667514*
Y0095206*
X066746*
Y0095152*
Y0095098*
X0667406*
Y0095043*
X0667352*
Y009499*
Y0094935*
X0667298*
Y0094881*
X0667244*
Y0094827*
Y0094773*
X066719*
Y0094719*
Y0094665*
X0667136*
Y0094611*
Y0094557*
X0667082*
Y0094503*
Y0094449*
X0667028*
Y0094395*
Y0094341*
X0666973*
Y0094287*
Y0094233*
Y0094178*
X0666919*
Y0094125*
Y009407*
Y0094016*
X0666865*
Y0093962*
Y0093908*
Y0093854*
Y00938*
X0666811*
Y0093746*
Y0093692*
Y0093638*
Y0093584*
Y009353*
Y0093476*
X0666757*
Y0093422*
Y0093368*
Y0093313*
Y009326*
Y0093205*
Y0093151*
Y0093097*
Y0093043*
Y0092989*
Y0092935*
Y0092881*
Y0092827*
Y0092773*
Y0092719*
Y0092665*
Y0092611*
X0666811*
Y0092557*
Y0092503*
Y0092449*
Y0092395*
Y009234*
Y0092286*
X0666865*
Y0092232*
Y0092178*
Y0092124*
Y009207*
X0666919*
Y0092016*
Y0091962*
Y0091908*
X0666973*
Y0091854*
Y00918*
Y0091746*
X0667028*
Y0091692*
Y0091638*
X0667082*
Y0091584*
Y009153*
X0667136*
Y0091475*
Y0091421*
X066719*
Y0091367*
Y0091313*
X0667244*
Y0091259*
Y0091205*
X0667298*
Y0091151*
X0667352*
Y0091097*
Y0091043*
X0667406*
Y0090989*
X066746*
Y0090935*
X0667514*
Y0090881*
Y0090827*
X0667568*
Y0090773*
X0667622*
Y0090719*
X0667676*
Y0090664*
X066773*
Y009061*
X0667784*
Y0090556*
X0667838*
Y0090502*
X0667893*
Y0090448*
X0667947*
Y0090394*
X0668001*
Y009034*
X0668109*
Y0090286*
X0668163*
Y0090232*
X0668217*
Y0090178*
X0668325*
Y0090124*
X0668379*
Y009007*
X0668487*
Y0090016*
X0668595*
Y0089962*
X0668649*
Y0089908*
X0668757*
Y0089854*
X066892*
Y0089799*
X0669028*
Y0089745*
X066919*
Y0089691*
X0669352*
Y0089637*
X0669568*
Y0089583*
X0669947*
Y0089529*
X0680327*
Y0089475*
X0680597*
Y0089421*
X0680813*
Y0089367*
X0680975*
Y0089313*
X0681138*
Y0089259*
X06813*
Y0089205*
X0681408*
Y0089151*
X0681516*
Y0089097*
X0681624*
Y0089043*
X0681732*
Y0088989*
X0681786*
Y0088934*
X0681895*
Y008888*
X0681949*
Y0088826*
X0682003*
Y0088772*
X0682111*
Y0088718*
X0682165*
Y0088664*
X0682219*
Y008861*
X0682273*
Y0088556*
X0682327*
Y0088502*
X0682381*
Y0088448*
X0682435*
Y0088394*
X0682489*
Y008834*
X0682543*
Y0088286*
X0682597*
Y0088232*
X0682652*
Y0088178*
X0682705*
Y0088124*
Y0088069*
X068276*
Y0088016*
X0682814*
Y0087961*
X0682868*
Y0087907*
Y0087853*
X0682922*
Y0087799*
Y0087745*
X0682976*
Y0087691*
X068303*
Y0087637*
Y0087583*
X0683084*
Y0087529*
Y0087475*
X0683138*
Y0087421*
Y0087367*
Y0087313*
X0683192*
Y0087259*
Y0087204*
X0683246*
Y0087151*
Y0087096*
Y0087042*
X06833*
Y0086988*
Y0086934*
Y008688*
Y0086826*
X0683354*
Y0086772*
Y0086718*
Y0086664*
Y008661*
Y0086556*
X0683408*
Y0086502*
Y0086448*
Y0086394*
Y0086339*
Y0086286*
Y0086231*
Y0086177*
Y0086123*
Y0086069*
Y0086015*
Y0085961*
Y0085907*
Y0085853*
Y0085799*
Y0085745*
Y0085691*
Y0085637*
Y0085583*
Y0085529*
Y0085474*
Y0085421*
X0683354*
Y0085366*
Y0085312*
Y0085258*
Y0085204*
Y008515*
X06833*
Y0085096*
Y0085042*
Y0084988*
X0683246*
Y0084934*
Y008488*
Y0084826*
X0683192*
Y0084772*
Y0084718*
Y0084664*
X0683138*
Y008461*
Y0084556*
X0683084*
Y0084501*
Y0084447*
X068303*
Y0084393*
Y0084339*
X0682976*
Y0084285*
Y0084231*
X0682922*
Y0084177*
Y0084123*
X0682868*
Y0084069*
X0682814*
Y0084015*
Y0083961*
X068276*
Y0083907*
X0682705*
Y0083853*
X0682652*
Y0083799*
X0682597*
Y0083745*
Y0083691*
X0682543*
Y0083636*
X0682489*
Y0083582*
X0682435*
Y0083528*
X0682381*
Y0083474*
X0682327*
Y008342*
X0682273*
Y0083366*
X0682219*
Y0083312*
X0682111*
Y0083258*
X0682057*
Y0083204*
X0682003*
Y008315*
X0681895*
Y0083096*
X0681841*
Y0083042*
X0681732*
Y0082988*
X0681678*
Y0082934*
X068157*
Y008288*
X0681462*
Y0082825*
X0681354*
Y0082771*
X0681246*
Y0082717*
X0681084*
Y0082663*
X0680922*
Y0082609*
X0680759*
Y0082555*
X0680489*
Y0082501*
X0680111*
Y0082447*
X0680002*
Y0082501*
X0679948*
Y0082447*
X066373*
Y0082501*
X0663676*
Y0082447*
X0663135*
Y0082393*
X0662865*
Y0082339*
X0662648*
Y0082285*
X0662486*
Y0082231*
X0662378*
Y0082177*
X0662216*
Y0082123*
X0662108*
Y0082069*
X0662*
Y0082015*
X0661946*
Y008196*
X0661838*
Y0081906*
X0661729*
Y0081852*
X0661675*
Y0081798*
X0661567*
Y0081744*
X0661513*
Y008169*
X0661459*
Y0081636*
X0661405*
Y0081582*
X0661297*
Y0081528*
X0661243*
Y0081474*
X0661189*
Y008142*
X0661135*
Y0081366*
X0661081*
Y0081312*
X0661027*
Y0081258*
Y0081204*
X0660973*
Y008115*
X0660919*
Y0081095*
X0660864*
Y0081042*
X066081*
Y0080987*
Y0080933*
X0660756*
Y0080879*
X0660702*
Y0080825*
Y0080771*
X0660648*
Y0080717*
X0660594*
Y0080663*
Y0080609*
X066054*
Y0080555*
Y0080501*
X0660486*
Y0080447*
Y0080393*
X0660432*
Y0080339*
Y0080285*
X0660378*
Y008023*
Y0080177*
Y0080122*
X0660324*
Y0080068*
Y0080014*
Y007996*
X066027*
Y0079906*
Y0079852*
Y0079798*
X0660216*
Y0079744*
Y007969*
Y0079636*
Y0079582*
Y0079528*
X0660162*
Y0079474*
Y007942*
Y0079365*
Y0079312*
Y0079257*
Y0079203*
Y0079149*
Y0079095*
Y0079041*
Y0078987*
Y0078933*
Y0078879*
Y0078825*
Y0078771*
Y0078717*
Y0078663*
Y0078609*
Y0078555*
Y00785*
Y0078447*
Y0078392*
X0660216*
Y0078338*
Y0078284*
Y007823*
Y0078176*
Y0078122*
X066027*
Y0078068*
Y0078014*
Y007796*
X0660324*
Y0077906*
Y0077852*
Y0077798*
X0660378*
Y0077744*
Y007769*
Y0077636*
X0660432*
Y0077582*
Y0077527*
X0660486*
Y0077473*
Y0077419*
X066054*
Y0077365*
Y0077311*
X0660594*
Y0077257*
Y0077203*
X0660648*
Y0077149*
Y0077095*
X0660702*
Y0077041*
X0660756*
Y0076987*
Y0076933*
X066081*
Y0076879*
X0660864*
Y0076825*
X0660919*
Y0076771*
Y0076717*
X0660973*
Y0076662*
X0661027*
Y0076608*
X0661081*
Y0076554*
X0661135*
Y00765*
X0661189*
Y0076446*
X0661243*
Y0076392*
X0661297*
Y0076338*
X0661351*
Y0076284*
X0661405*
Y007623*
X0661513*
Y0076176*
X0661567*
Y0076122*
X0661621*
Y0076068*
X0661729*
Y0076014*
X0661784*
Y007596*
X0661892*
Y0075906*
X0662*
Y0075852*
X0662108*
Y0075797*
X0662216*
Y0075743*
X0662324*
Y0075689*
X0662486*
Y0075635*
X0662595*
Y0075581*
X0662811*
Y0075527*
X0663081*
Y0075473*
X0663568*
Y0075419*
X0674758*
Y0075365*
X0675029*
Y0075311*
X0675191*
Y0075257*
X0675353*
Y0075203*
X0675515*
Y0075149*
X0675677*
Y0075095*
X0675786*
Y0075041*
X0675894*
Y0074986*
X0675948*
Y0074932*
X0676056*
Y0074878*
X0676164*
Y0074824*
X0676218*
Y007477*
X0676326*
Y0074716*
X067638*
Y0074662*
X0676434*
Y0074608*
X0676488*
Y0074554*
X0676596*
Y00745*
X0676651*
Y0074446*
X0676705*
Y0074392*
X0676759*
Y0074338*
X0676813*
Y0074284*
X0676867*
Y007423*
Y0074176*
X0676921*
Y0074121*
X0676975*
Y0074067*
X0677029*
Y0074013*
X0677083*
Y0073959*
Y0073905*
X0677137*
Y0073851*
X0677191*
Y0073797*
Y0073743*
X0677245*
Y0073689*
X0677299*
Y0073635*
Y0073581*
X0677353*
Y0073527*
Y0073473*
X0677407*
Y0073419*
Y0073365*
X0677461*
Y0073311*
Y0073256*
X0677516*
Y0073203*
Y0073148*
Y0073094*
X067757*
Y007304*
Y0072986*
Y0072932*
X0677624*
Y0072878*
Y0072824*
Y007277*
X0677678*
Y0072716*
Y0072662*
Y0072608*
Y0072554*
Y00725*
Y0072446*
X0677732*
Y0072391*
Y0072338*
Y0072283*
Y0072229*
Y0072175*
Y0072121*
Y0072067*
Y0072013*
Y0071959*
X0677786*
Y0071905*
Y0071851*
X0677732*
Y0071797*
Y0071743*
Y0071689*
Y0071635*
Y0071581*
Y0071526*
Y0071473*
Y0071418*
Y0071364*
Y007131*
X0677678*
Y0071256*
Y0071202*
Y0071148*
Y0071094*
Y007104*
X0677624*
Y0070986*
Y0070932*
Y0070878*
X067757*
Y0070824*
Y007077*
Y0070716*
X0677516*
Y0070662*
Y0070608*
Y0070553*
X0677461*
Y0070499*
Y0070445*
Y0070391*
X0677407*
Y0070337*
Y0070283*
X0677353*
Y0070229*
Y0070175*
X0677299*
Y0070121*
Y0070067*
X0677245*
Y0070013*
X0677191*
Y0069959*
Y0069905*
X0677137*
Y0069851*
X0677083*
Y0069797*
Y0069743*
X0677029*
Y0069688*
X0676975*
Y0069634*
X0676921*
Y006958*
Y0069526*
X0676867*
Y0069472*
X0676813*
Y0069418*
X0676759*
Y0069364*
X0676705*
Y006931*
X0676651*
Y0069256*
X0676596*
Y0069202*
X0676543*
Y0069148*
X0676488*
Y0069094*
X0676434*
Y006904*
X067638*
Y0068986*
X0676272*
Y0068932*
X0676218*
Y0068878*
X0676164*
Y0068823*
X0676056*
Y0068769*
X0676002*
Y0068715*
X0675894*
Y0068661*
X0675786*
Y0068607*
X0675677*
Y0068553*
X0675569*
Y0068499*
X0675407*
Y0068445*
X0675191*
Y0068391*
X0636266*
Y0068337*
X0636158*
Y0068283*
X0636104*
Y0068229*
X063605*
Y0068175*
X0635996*
Y0068121*
Y0068067*
X0635942*
Y0068012*
Y0067958*
Y0067904*
Y006785*
Y0067796*
Y0067742*
Y0067688*
Y0067634*
Y006758*
Y0067526*
Y0067472*
Y0067418*
Y0067364*
Y006731*
Y0067256*
Y0067202*
Y0067147*
Y0067093*
Y0067039*
Y0066985*
Y0066931*
Y0066877*
Y0066823*
Y0066769*
Y0066715*
Y0066661*
Y0066607*
Y0066553*
Y0066499*
Y0066445*
Y0066391*
Y0066337*
Y0066282*
Y0066228*
Y0066174*
Y006612*
Y0066066*
Y0066012*
Y0065958*
Y0065904*
Y006585*
Y0065796*
Y0065742*
Y0065688*
Y0065634*
Y006558*
Y0065526*
Y0065472*
Y0065417*
Y0065364*
Y0065309*
Y0065255*
Y0065201*
Y0065147*
Y0065093*
Y0065039*
Y0064985*
Y0064931*
Y0064877*
Y0064823*
Y0064769*
Y0064715*
Y0064661*
Y0064607*
Y0064552*
Y0064499*
Y0064444*
Y006439*
Y0064336*
Y0064282*
Y0064228*
Y0064174*
Y006412*
Y0064066*
Y0064012*
Y0063958*
Y0063904*
Y006385*
Y0063796*
Y0063742*
Y0063688*
Y0063634*
Y0063579*
Y0063525*
Y0063471*
Y0063417*
Y0063363*
Y0063309*
Y0063255*
Y0063201*
Y0063147*
Y0063093*
Y0063039*
Y0062985*
Y0062931*
Y0062877*
Y0062823*
Y0062769*
Y0062714*
X0635888*
Y006266*
Y0062606*
X0635834*
Y0062552*
Y0062498*
X063578*
Y0062444*
X0635672*
Y006239*
X0635564*
Y0062336*
X0625238*
Y006239*
X0625075*
Y0062444*
X0625021*
Y0062498*
X0624967*
Y0062552*
X0624913*
Y0062606*
Y006266*
X0624859*
Y0062714*
Y0062769*
Y0062823*
Y0062877*
Y0062931*
Y0062985*
Y0063039*
Y0063093*
Y0063147*
Y0063201*
Y0063255*
Y0063309*
Y0063363*
Y0063417*
Y0063471*
Y0063525*
Y0063579*
Y0063634*
Y0063688*
Y0063742*
Y0063796*
Y006385*
Y0063904*
Y0063958*
Y0064012*
Y0064066*
Y006412*
Y0064174*
Y0064228*
Y0064282*
Y0064336*
Y006439*
Y0064444*
Y0064499*
Y0064552*
Y0064607*
Y0064661*
Y0064715*
Y0064769*
Y0064823*
Y0064877*
Y0064931*
Y0064985*
Y0065039*
Y0065093*
Y0065147*
Y0065201*
Y0065255*
Y0065309*
Y0065364*
Y0065417*
Y0065472*
Y0065526*
Y006558*
Y0065634*
Y0065688*
Y0065742*
Y0065796*
Y006585*
Y0065904*
Y0065958*
X0624805*
Y0066012*
Y0066066*
Y006612*
X0624751*
Y0066174*
Y0066228*
X0624697*
Y0066282*
X0624589*
Y0066337*
X0624427*
Y0066391*
X0624264*
Y0066337*
X0624102*
Y0066282*
X0624048*
Y0066228*
X0623994*
Y0066174*
X062394*
Y006612*
X0623886*
Y0066066*
Y0066012*
Y0065958*
Y0065904*
X0623832*
Y006585*
Y0065796*
Y0065742*
Y0065688*
Y0065634*
Y006558*
Y0065526*
Y0065472*
Y0065417*
Y0065364*
Y0065309*
Y0065255*
Y0065201*
Y0065147*
Y0065093*
Y0065039*
Y0064985*
Y0064931*
Y0064877*
Y0064823*
Y0064769*
Y0064715*
Y0064661*
Y0064607*
Y0064552*
Y0064499*
Y0064444*
Y006439*
Y0064336*
Y0064282*
Y0064228*
Y0064174*
Y006412*
Y0064066*
Y0064012*
Y0063958*
Y0063904*
Y006385*
Y0063796*
Y0063742*
Y0063688*
Y0063634*
Y0063579*
Y0063525*
Y0063471*
Y0063417*
Y0063363*
Y0063309*
Y0063255*
Y0063201*
Y0063147*
Y0063093*
Y0063039*
Y0062985*
Y0062931*
Y0062877*
Y0062823*
Y0062769*
Y0062714*
Y006266*
Y0062606*
X0623778*
Y0062552*
X0623724*
Y0062498*
X062367*
Y0062444*
X0623616*
Y006239*
X0623454*
Y0062336*
X0618155*
Y006239*
X0618047*
Y0062444*
X0617939*
Y0062498*
X0617885*
Y0062552*
Y0062606*
X0617831*
Y006266*
Y0062714*
Y0062769*
X0617777*
Y0062823*
Y0062877*
Y0062931*
Y0062985*
Y0063039*
Y0063093*
Y0063147*
Y0063201*
Y0063255*
Y0063309*
Y0063363*
Y0063417*
Y0063471*
Y0063525*
Y0063579*
Y0063634*
Y0063688*
Y0063742*
Y0063796*
Y006385*
Y0063904*
Y0063958*
Y0064012*
Y0064066*
Y006412*
Y0064174*
Y0064228*
Y0064282*
Y0064336*
Y006439*
Y0064444*
Y0064499*
Y0064552*
Y0064607*
Y0064661*
Y0064715*
Y0064769*
Y0064823*
Y0064877*
Y0064931*
Y0064985*
Y0065039*
Y0065093*
Y0065147*
Y0065201*
Y0065255*
Y0065309*
Y0065364*
Y0065417*
Y0065472*
Y0065526*
Y006558*
Y0065634*
Y0065688*
Y0065742*
Y0065796*
Y006585*
Y0065904*
Y0065958*
Y0066012*
Y0066066*
Y006612*
Y0066174*
Y0066228*
Y0066282*
Y0066337*
Y0066391*
Y0066445*
Y0066499*
Y0066553*
Y0066607*
Y0066661*
Y0066715*
Y0066769*
Y0066823*
Y0066877*
Y0066931*
Y0066985*
Y0067039*
Y0067093*
Y0067147*
X0617831*
Y0067202*
X0617777*
Y0067256*
Y006731*
Y0067364*
Y0067418*
Y0067472*
Y0067526*
Y006758*
Y0067634*
Y0067688*
X0617723*
Y0067742*
Y0067796*
X0617669*
Y006785*
Y0067904*
X0617615*
Y0067958*
Y0068012*
X0617561*
Y0068067*
X0617507*
Y0068121*
X0617453*
Y0068175*
X0617399*
Y0068229*
X061729*
Y0068283*
X0617182*
Y0068337*
X061702*
Y0068391*
X0616588*
Y0068337*
X0616426*
Y0068283*
X0616317*
Y0068229*
X0616209*
Y0068175*
X0616155*
Y0068121*
X0616101*
Y0068067*
X0616047*
Y0068012*
X0615993*
Y0067958*
X0615939*
Y0067904*
Y006785*
X0615885*
Y0067796*
Y0067742*
X0615831*
Y0067688*
Y0067634*
Y006758*
Y0067526*
Y0067472*
Y0067418*
X0615777*
Y0067364*
X0615831*
Y006731*
Y0067256*
X0615777*
Y0067202*
X0615831*
Y0067147*
Y0067093*
Y0067039*
Y0066985*
Y0066931*
Y0066877*
Y0066823*
Y0066769*
Y0066715*
Y0066661*
Y0066607*
Y0066553*
Y0066499*
Y0066445*
Y0066391*
Y0066337*
Y0066282*
Y0066228*
Y0066174*
Y006612*
Y0066066*
Y0066012*
Y0065958*
Y0065904*
Y006585*
Y0065796*
Y0065742*
Y0065688*
Y0065634*
Y006558*
Y0065526*
Y0065472*
Y0065417*
Y0065364*
Y0065309*
Y0065255*
Y0065201*
Y0065147*
Y0065093*
Y0065039*
Y0064985*
Y0064931*
Y0064877*
X0615777*
Y0064823*
Y0064769*
Y0064715*
Y0064661*
X0615723*
Y0064607*
X0615669*
Y0064552*
X0615615*
Y0064499*
X061556*
Y0064444*
X0615398*
Y006439*
X0612155*
Y0064444*
X0611992*
Y0064499*
X0611938*
Y0064552*
X0611884*
Y0064607*
X061183*
Y0064661*
X0611776*
Y0064715*
Y0064769*
Y0064823*
X0611722*
Y0064877*
Y0064931*
Y0064985*
Y0065039*
Y0065093*
Y0065147*
Y0065201*
Y0065255*
Y0065309*
Y0065364*
Y0065417*
Y0065472*
Y0065526*
Y006558*
Y0065634*
Y0065688*
Y0065742*
Y0065796*
Y006585*
Y0065904*
Y0065958*
Y0066012*
Y0066066*
Y006612*
Y0066174*
Y0066228*
Y0066282*
Y0066337*
Y0066391*
Y0066445*
Y0066499*
Y0066553*
Y0066607*
Y0066661*
Y0066715*
Y0066769*
Y0066823*
Y0066877*
Y0066931*
Y0066985*
Y0067039*
Y0067093*
Y0067147*
Y0067202*
Y0067256*
Y006731*
Y0067364*
Y0067418*
Y0067472*
Y0067526*
Y006758*
X0611776*
Y0067634*
Y0067688*
X0611722*
Y0067742*
X0611776*
Y0067796*
X0611722*
Y006785*
Y0067904*
Y0067958*
Y0068012*
Y0068067*
Y0068121*
X0611668*
Y0068175*
Y0068229*
X0611614*
Y0068283*
X0611506*
Y0068337*
X0611398*
Y0068391*
X0603018*
Y0068337*
X060291*
Y0068283*
X0602856*
Y0068229*
X0602802*
Y0068175*
X0602748*
Y0068121*
Y0068067*
X0602694*
Y0068012*
Y0067958*
Y0067904*
Y006785*
Y0067796*
Y0067742*
Y0067688*
Y0067634*
Y006758*
Y0067526*
Y0067472*
Y0067418*
Y0067364*
Y006731*
Y0067256*
Y0067202*
Y0067147*
Y0067093*
Y0067039*
Y0066985*
Y0066931*
Y0066877*
Y0066823*
Y0066769*
Y0066715*
Y0066661*
Y0066607*
Y0066553*
Y0066499*
Y0066445*
Y0066391*
Y0066337*
Y0066282*
Y0066228*
Y0066174*
Y006612*
Y0066066*
Y0066012*
Y0065958*
Y0065904*
Y006585*
Y0065796*
Y0065742*
Y0065688*
Y0065634*
Y006558*
Y0065526*
Y0065472*
Y0065417*
Y0065364*
Y0065309*
Y0065255*
Y0065201*
Y0065147*
Y0065093*
Y0065039*
Y0064985*
Y0064931*
Y0064877*
Y0064823*
Y0064769*
Y0064715*
Y0064661*
Y0064607*
Y0064552*
Y0064499*
Y0064444*
Y006439*
Y0064336*
Y0064282*
Y0064228*
Y0064174*
Y006412*
Y0064066*
Y0064012*
Y0063958*
Y0063904*
Y006385*
Y0063796*
Y0063742*
Y0063688*
Y0063634*
Y0063579*
Y0063525*
Y0063471*
Y0063417*
Y0063363*
X0594638*
Y0063417*
Y0063471*
Y0063525*
Y0063579*
Y0063634*
Y0063688*
Y0063742*
Y0063796*
Y006385*
Y0063904*
Y0063958*
Y0064012*
Y0064066*
Y006412*
Y0064174*
Y0064228*
Y0064282*
Y0064336*
Y006439*
Y0064444*
Y0064499*
Y0064552*
Y0064607*
Y0064661*
Y0064715*
Y0064769*
Y0064823*
Y0064877*
Y0064931*
Y0064985*
Y0065039*
Y0065093*
Y0065147*
Y0065201*
Y0065255*
Y0065309*
Y0065364*
Y0065417*
Y0065472*
Y0065526*
Y006558*
Y0065634*
Y0065688*
Y0065742*
Y0065796*
Y006585*
Y0065904*
Y0065958*
Y0066012*
Y0066066*
Y006612*
Y0066174*
Y0066228*
Y0066282*
Y0066337*
Y0066391*
Y0066445*
Y0066499*
Y0066553*
Y0066607*
Y0066661*
Y0066715*
Y0066769*
Y0066823*
Y0066877*
Y0066931*
Y0066985*
Y0067039*
Y0067093*
Y0067147*
Y0067202*
Y0067256*
Y006731*
Y0067364*
Y0067418*
Y0067472*
Y0067526*
Y006758*
Y0067634*
Y0067688*
Y0067742*
Y0067796*
Y006785*
Y0067904*
Y0067958*
Y0068012*
Y0068067*
Y0068121*
Y0068175*
Y0068229*
X0599883*
Y0068283*
Y0068337*
Y0068391*
Y0068445*
Y0068499*
Y0068553*
Y0068607*
Y0068661*
Y0068715*
Y0068769*
Y0068823*
Y0068878*
Y0068932*
Y0068986*
Y006904*
Y0069094*
Y0069148*
Y0069202*
Y0069256*
Y006931*
Y0069364*
Y0069418*
Y0069472*
Y0069526*
Y006958*
Y0069634*
Y0069688*
Y0069743*
Y0069797*
Y0069851*
Y0069905*
Y0069959*
Y0070013*
Y0070067*
Y0070121*
Y0070175*
Y0070229*
Y0070283*
Y0070337*
Y0070391*
Y0070445*
Y0070499*
Y0070553*
Y0070608*
Y0070662*
Y0070716*
Y007077*
Y0070824*
Y0070878*
Y0070932*
Y0070986*
Y007104*
Y0071094*
Y0071148*
Y0071202*
Y0071256*
Y007131*
Y0071364*
Y0071418*
Y0071473*
Y0071526*
Y0071581*
Y0071635*
Y0071689*
Y0071743*
Y0071797*
Y0071851*
Y0071905*
Y0071959*
Y0072013*
Y0072067*
Y0072121*
Y0072175*
Y0072229*
Y0072283*
Y0072338*
Y0072391*
Y0072446*
Y00725*
Y0072554*
Y0072608*
Y0072662*
Y0072716*
Y007277*
Y0072824*
Y0072878*
Y0072932*
Y0072986*
Y007304*
Y0073094*
Y0073148*
Y0073203*
Y0073256*
Y0073311*
Y0073365*
Y0073419*
Y0073473*
Y0073527*
Y0073581*
Y0073635*
Y0073689*
Y0073743*
Y0073797*
Y0073851*
Y0073905*
Y0073959*
Y0074013*
Y0074067*
Y0074121*
Y0074176*
X0594638*
Y007423*
Y0074284*
Y0074338*
Y0074392*
Y0074446*
Y00745*
Y0074554*
Y0074608*
Y0074662*
Y0074716*
Y007477*
Y0074824*
Y0074878*
Y0074932*
Y0074986*
Y0075041*
Y0075095*
Y0075149*
Y0075203*
Y0075257*
Y0075311*
Y0075365*
Y0075419*
Y0075473*
Y0075527*
X0599883*
Y0075581*
Y0075635*
Y0075689*
Y0075743*
Y0075797*
Y0075852*
Y0075906*
Y007596*
Y0076014*
Y0076068*
Y0076122*
Y0076176*
Y007623*
Y0076284*
Y0076338*
Y0076392*
Y0076446*
Y00765*
Y0076554*
Y0076608*
Y0076662*
Y0076717*
Y0076771*
Y0076825*
Y0076879*
Y0076933*
Y0076987*
Y0077041*
Y0077095*
Y0077149*
Y0077203*
Y0077257*
Y0077311*
Y0077365*
Y0077419*
Y0077473*
Y0077527*
Y0077582*
Y0077636*
Y007769*
Y0077744*
Y0077798*
Y0077852*
Y0077906*
Y007796*
Y0078014*
Y0078068*
Y0078122*
Y0078176*
Y007823*
Y0078284*
Y0078338*
Y0078392*
Y0078447*
Y00785*
Y0078555*
Y0078609*
Y0078663*
Y0078717*
Y0078771*
Y0078825*
Y0078879*
Y0078933*
Y0078987*
Y0079041*
Y0079095*
Y0079149*
Y0079203*
Y0079257*
Y0079312*
Y0079365*
Y007942*
Y0079474*
Y0079528*
Y0079582*
Y0079636*
Y007969*
Y0079744*
Y0079798*
Y0079852*
Y0079906*
Y007996*
Y0080014*
Y0080068*
Y0080122*
Y0080177*
Y008023*
Y0080285*
Y0080339*
Y0080393*
Y0080447*
Y0080501*
Y0080555*
Y0080609*
Y0080663*
Y0080717*
Y0080771*
Y0080825*
Y0080879*
Y0080933*
Y0080987*
Y0081042*
Y0081095*
Y008115*
Y0081204*
Y0081258*
Y0081312*
Y0081366*
Y008142*
Y0081474*
X0594693*
Y0081528*
X0594638*
Y0081582*
Y0081636*
Y008169*
Y0081744*
Y0081798*
Y0081852*
Y0081906*
Y008196*
Y0082015*
Y0082069*
Y0082123*
Y0082177*
Y0082231*
Y0082285*
Y0082339*
Y0082393*
Y0082447*
Y0082501*
Y0082555*
Y0082609*
Y0082663*
Y0082717*
Y0082771*
Y0082825*
X0599883*
Y008288*
Y0082934*
Y0082988*
Y0083042*
Y0083096*
Y008315*
Y0083204*
Y0083258*
Y0083312*
Y0083366*
Y008342*
Y0083474*
Y0083528*
Y0083582*
Y0083636*
Y0083691*
Y0083745*
Y0083799*
Y0083853*
Y0083907*
Y0083961*
Y0084015*
Y0084069*
Y0084123*
Y0084177*
Y0084231*
Y0084285*
Y0084339*
Y0084393*
Y0084447*
Y0084501*
Y0084556*
Y008461*
Y0084664*
Y0084718*
Y0084772*
Y0084826*
Y008488*
Y0084934*
Y0084988*
Y0085042*
Y0085096*
Y008515*
Y0085204*
Y0085258*
Y0085312*
Y0085366*
Y0085421*
Y0085474*
Y0085529*
Y0085583*
Y0085637*
Y0085691*
Y0085745*
Y0085799*
Y0085853*
Y0085907*
Y0085961*
Y0086015*
Y0086069*
Y0086123*
Y0086177*
Y0086231*
Y0086286*
Y0086339*
Y0086394*
Y0086448*
Y0086502*
Y0086556*
Y008661*
Y0086664*
Y0086718*
Y0086772*
Y0086826*
Y008688*
Y0086934*
Y0086988*
Y0087042*
Y0087096*
Y0087151*
Y0087204*
Y0087259*
Y0087313*
Y0087367*
Y0087421*
Y0087475*
Y0087529*
Y0087583*
Y0087637*
Y0087691*
Y0087745*
Y0087799*
Y0087853*
Y0087907*
Y0087961*
Y0088016*
Y0088069*
Y0088124*
Y0088178*
Y0088232*
Y0088286*
Y008834*
Y0088394*
Y0088448*
Y0088502*
Y0088556*
Y008861*
Y0088664*
Y0088718*
Y0088772*
Y0088826*
X0594638*
Y008888*
Y0088934*
Y0088989*
Y0089043*
Y0089097*
Y0089151*
Y0089205*
Y0089259*
Y0089313*
Y0089367*
Y0089421*
Y0089475*
Y0089529*
Y0089583*
Y0089637*
Y0089691*
Y0089745*
Y0089799*
Y0089854*
Y0089908*
Y0089962*
Y0090016*
Y009007*
Y0090124*
X0594693*
Y0090178*
X0599883*
Y0090232*
Y0090286*
Y009034*
Y0090394*
Y0090448*
Y0090502*
Y0090556*
Y009061*
Y0090664*
Y0090719*
Y0090773*
Y0090827*
Y0090881*
Y0090935*
Y0090989*
Y0091043*
Y0091097*
Y0091151*
Y0091205*
Y0091259*
Y0091313*
Y0091367*
Y0091421*
Y0091475*
Y009153*
Y0091584*
Y0091638*
Y0091692*
Y0091746*
Y00918*
Y0091854*
Y0091908*
Y0091962*
Y0092016*
Y009207*
Y0092124*
Y0092178*
Y0092232*
Y0092286*
Y009234*
Y0092395*
Y0092449*
Y0092503*
Y0092557*
Y0092611*
Y0092665*
Y0092719*
Y0092773*
Y0092827*
Y0092881*
Y0092935*
Y0092989*
Y0093043*
Y0093097*
Y0093151*
Y0093205*
Y009326*
Y0093313*
Y0093368*
Y0093422*
Y0093476*
Y009353*
Y0093584*
Y0093638*
Y0093692*
Y0093746*
Y00938*
Y0093854*
Y0093908*
Y0093962*
Y0094016*
Y009407*
Y0094125*
Y0094178*
Y0094233*
Y0094287*
Y0094341*
Y0094395*
Y0094449*
Y0094503*
Y0094557*
Y0094611*
Y0094665*
Y0094719*
Y0094773*
Y0094827*
Y0094881*
Y0094935*
Y009499*
Y0095043*
Y0095098*
Y0095152*
Y0095206*
Y009526*
Y0095314*
Y0095368*
Y0095422*
Y0095476*
Y009553*
Y0095584*
Y0095638*
Y0095692*
Y0095746*
Y00958*
Y0095854*
Y0095908*
Y0095963*
Y0096017*
Y0096071*
Y0096125*
X0594638*
Y0096179*
Y0096233*
Y0096287*
Y0096341*
Y0096395*
Y0096449*
Y0096503*
Y0096557*
Y0096611*
Y0096665*
Y0096719*
Y0096773*
Y0096828*
Y0096882*
Y0096936*
Y009699*
Y0097044*
Y0097098*
Y0097152*
Y0097206*
Y009726*
Y0097314*
Y0097368*
Y0097422*
Y0097476*
Y009753*
Y0097584*
Y0097638*
Y0097693*
Y0097747*
Y0097801*
Y0097855*
Y0097909*
Y0097963*
Y0098017*
Y0098071*
Y0098125*
Y0098179*
Y0098233*
Y0098287*
Y0098341*
Y0098395*
Y0098449*
Y0098504*
Y0098558*
Y0098612*
Y0098666*
Y009872*
Y0098774*
Y0098828*
Y0098882*
Y0098936*
Y009899*
Y0099044*
Y0099098*
Y0099152*
Y0099206*
Y009926*
Y0099314*
Y0099369*
Y0099423*
Y0099477*
Y0099531*
Y0099585*
Y0099639*
Y0099693*
Y0099747*
Y0099801*
Y0099855*
Y0099909*
Y0099963*
Y0100017*
Y0100071*
Y0100125*
Y0100179*
Y0100233*
Y0100287*
Y0100342*
Y0100396*
Y010045*
Y0100504*
Y0100558*
Y0100612*
Y0100666*
Y010072*
Y0100774*
Y0100828*
Y0100882*
Y0100936*
Y010099*
Y0101044*
Y0101099*
Y0101153*
Y0101207*
Y0101261*
Y0101315*
Y0101369*
Y0101423*
Y0101477*
Y0101531*
Y0101585*
Y0101639*
Y0101693*
Y0101747*
Y0101801*
Y0101855*
Y0101909*
Y0101963*
Y0102017*
Y0102072*
Y0102126*
Y010218*
Y0102234*
Y0102288*
Y0102342*
Y0102396*
Y010245*
Y0102504*
Y0102558*
Y0102612*
Y0102666*
Y010272*
Y0102774*
Y0102828*
Y0102883*
Y0102937*
Y0102991*
Y0103045*
Y0103099*
Y0103153*
Y0103207*
Y0103261*
Y0103315*
Y0103369*
Y0103423*
Y0103477*
Y0103531*
Y0103585*
Y0103639*
Y0103693*
Y0103747*
Y0103802*
Y0103856*
Y010391*
Y0103964*
Y0104018*
Y0104072*
Y0104126*
Y010418*
Y0104234*
Y0104288*
Y0104342*
Y0104396*
Y010445*
Y0104504*
Y0104558*
Y0104613*
Y0104667*
Y0104721*
Y0104775*
Y0104829*
Y0104883*
Y0104937*
Y0104991*
Y0105045*
Y0105099*
Y0105153*
Y0105207*
Y0105261*
Y0105315*
Y0105369*
Y0105423*
Y0105477*
Y0105532*
Y0105586*
Y010564*
Y0105694*
Y0105748*
Y0105802*
Y0105856*
Y010591*
Y0105964*
Y0106018*
Y0106072*
Y0106126*
Y010618*
Y0106234*
Y0106288*
Y0106342*
Y0106397*
Y0106451*
Y0106505*
Y0106559*
Y0106613*
Y0106667*
Y0106721*
Y0106775*
Y0106829*
Y0106883*
Y0106937*
Y0106991*
Y0107045*
Y0107099*
Y0107153*
Y0107208*
Y0107262*
Y0107316*
Y010737*
Y0107424*
Y0107478*
Y0107532*
Y0107586*
Y010764*
Y0107694*
Y0107748*
Y0107802*
Y0107856*
Y010791*
Y0107964*
Y0108018*
Y0108072*
Y0108126*
Y0108181*
Y0108235*
Y0108289*
Y0108343*
Y0108397*
Y0108451*
Y0108505*
Y0108559*
Y0108613*
Y0108667*
Y0108721*
Y0108775*
Y0108829*
Y0108883*
Y0108938*
Y0108992*
Y0109046*
Y01091*
Y0109154*
Y0109208*
Y0109262*
Y0109316*
Y010937*
Y0109424*
Y0109478*
Y0109532*
Y0109586*
Y010964*
Y0109694*
Y0109748*
Y0109802*
Y0109856*
Y0109911*
Y0109965*
Y0110019*
Y0110073*
Y0110127*
Y0110181*
Y0110235*
Y0110289*
Y0110343*
Y0110397*
Y0110451*
Y0110505*
Y0110559*
Y0110613*
Y0110668*
Y0110722*
Y0110776*
Y011083*
Y0110884*
Y0110938*
Y0110992*
Y0111046*
Y01111*
Y0111154*
Y0111208*
Y0111262*
Y0111316*
Y011137*
Y0111424*
Y0111478*
Y0111532*
Y0111586*
Y0111641*
Y0111695*
Y0111749*
Y0111803*
Y0111857*
Y0111911*
Y0111965*
Y0112019*
Y0112073*
Y0112127*
Y0112181*
Y0112235*
Y0112289*
Y0112343*
Y0112397*
Y0112452*
Y0112505*
Y011256*
Y0112614*
Y0112668*
Y0112722*
Y0112776*
Y011283*
Y0112884*
Y0112938*
Y0112992*
Y0113046*
Y01131*
Y0113154*
Y0113208*
Y0113262*
Y0113317*
Y0113371*
Y0113425*
Y0113479*
Y0113533*
Y0113587*
Y0113641*
Y0113695*
Y0113749*
Y0113803*
Y0113857*
Y0113911*
Y0113965*
Y0114019*
Y0114073*
Y0114127*
Y0114181*
Y0114235*
Y011429*
Y0114344*
Y0114398*
Y0114452*
Y0114506*
Y011456*
Y0114614*
Y0114668*
Y0114722*
Y0114776*
Y011483*
Y0114884*
Y0114938*
Y0114992*
Y0115047*
Y0115101*
Y0115155*
Y0115209*
Y0115263*
Y0115317*
Y0115371*
Y0115425*
Y0115479*
Y0115533*
Y0115587*
Y0115641*
Y0115695*
Y0115749*
Y0115803*
Y0115857*
Y0115911*
Y0115965*
Y011602*
Y0116074*
Y0116128*
Y0116182*
Y0116236*
Y011629*
Y0116344*
Y0116398*
Y0116452*
Y0116506*
Y011656*
Y0116614*
Y0116668*
Y0116722*
Y0116776*
Y0116831*
Y0116885*
Y0116939*
Y0116993*
Y0117047*
Y0117101*
Y0117155*
Y0117209*
Y0117263*
Y0117317*
Y0117371*
Y0117425*
Y0117479*
Y0117533*
Y0117587*
Y0117641*
Y0117695*
X0594693*
Y011775*
X0662919*
Y0117695*
G37*
G36*
X0597125Y0080501D02*
X0597396D01*
Y0080447*
X0597558*
Y0080393*
X059772*
Y0080339*
X0597828*
Y0080285*
X0597936*
Y008023*
X059799*
Y0080177*
X0598099*
Y0080122*
X0598152*
Y0080068*
X0598207*
Y0080014*
X0598261*
Y007996*
X0598315*
Y0079906*
X0598369*
Y0079852*
X0598423*
Y0079798*
X0598477*
Y0079744*
X0598531*
Y007969*
Y0079636*
X0598585*
Y0079582*
X0598639*
Y0079528*
Y0079474*
X0598693*
Y007942*
Y0079365*
X0598747*
Y0079312*
Y0079257*
X0598801*
Y0079203*
Y0079149*
Y0079095*
X0598855*
Y0079041*
Y0078987*
Y0078933*
Y0078879*
X0598909*
Y0078825*
Y0078771*
Y0078717*
Y0078663*
Y0078609*
Y0078555*
Y00785*
Y0078447*
Y0078392*
Y0078338*
Y0078284*
Y007823*
Y0078176*
X0598855*
Y0078122*
Y0078068*
Y0078014*
Y007796*
X0598801*
Y0077906*
Y0077852*
Y0077798*
X0598747*
Y0077744*
Y007769*
Y0077636*
X0598693*
Y0077582*
Y0077527*
X0598639*
Y0077473*
X0598585*
Y0077419*
Y0077365*
X0598531*
Y0077311*
X0598477*
Y0077257*
Y0077203*
X0598423*
Y0077149*
X0598369*
Y0077095*
X0598315*
Y0077041*
X0598261*
Y0076987*
X0598207*
Y0076933*
X0598099*
Y0076879*
X0598044*
Y0076825*
X0597936*
Y0076771*
X0597882*
Y0076717*
X0597774*
Y0076662*
X0597612*
Y0076608*
X0597504*
Y0076554*
X0597288*
Y00765*
X0596477*
Y0076554*
X0596314*
Y0076608*
X0596152*
Y0076662*
X059599*
Y0076717*
X0595936*
Y0076771*
X0595828*
Y0076825*
X059572*
Y0076879*
X0595666*
Y0076933*
X0595612*
Y0076987*
X0595504*
Y0077041*
X0595449*
Y0077095*
X0595395*
Y0077149*
X0595341*
Y0077203*
Y0077257*
X0595287*
Y0077311*
X0595233*
Y0077365*
X0595179*
Y0077419*
Y0077473*
X0595125*
Y0077527*
Y0077582*
X0595071*
Y0077636*
Y007769*
X0595017*
Y0077744*
Y0077798*
X0594963*
Y0077852*
Y0077906*
Y007796*
X0594909*
Y0078014*
Y0078068*
Y0078122*
Y0078176*
Y007823*
X0594855*
Y0078284*
Y0078338*
Y0078392*
Y0078447*
Y00785*
Y0078555*
Y0078609*
Y0078663*
Y0078717*
Y0078771*
X0594909*
Y0078825*
Y0078879*
Y0078933*
Y0078987*
Y0079041*
X0594963*
Y0079095*
Y0079149*
Y0079203*
X0595017*
Y0079257*
Y0079312*
Y0079365*
X0595071*
Y007942*
Y0079474*
X0595125*
Y0079528*
Y0079582*
X0595179*
Y0079636*
X0595233*
Y007969*
Y0079744*
X0595287*
Y0079798*
X0595341*
Y0079852*
X0595395*
Y0079906*
X0595449*
Y007996*
X0595504*
Y0080014*
X0595558*
Y0080068*
X0595612*
Y0080122*
X0595666*
Y0080177*
X0595774*
Y008023*
X0595882*
Y0080285*
X0595936*
Y0080339*
X0596044*
Y0080393*
X0596206*
Y0080447*
X0596369*
Y0080501*
X0596639*
Y0080555*
X0597125*
Y0080501*
G37*
G36*
X0597342Y0073148D02*
X0597558D01*
Y0073094*
X0597666*
Y007304*
X0597774*
Y0072986*
X0597882*
Y0072932*
X059799*
Y0072878*
X0598044*
Y0072824*
X0598152*
Y007277*
X0598207*
Y0072716*
X0598261*
Y0072662*
X0598315*
Y0072608*
X0598369*
Y0072554*
X0598423*
Y00725*
X0598477*
Y0072446*
X0598531*
Y0072391*
Y0072338*
X0598585*
Y0072283*
X0598639*
Y0072229*
Y0072175*
X0598693*
Y0072121*
Y0072067*
X0598747*
Y0072013*
Y0071959*
X0598801*
Y0071905*
Y0071851*
Y0071797*
X0598855*
Y0071743*
Y0071689*
Y0071635*
Y0071581*
Y0071526*
X0598909*
Y0071473*
Y0071418*
Y0071364*
Y007131*
Y0071256*
Y0071202*
Y0071148*
Y0071094*
Y007104*
Y0070986*
Y0070932*
Y0070878*
X0598855*
Y0070824*
Y007077*
Y0070716*
Y0070662*
Y0070608*
X0598801*
Y0070553*
Y0070499*
Y0070445*
X0598747*
Y0070391*
Y0070337*
X0598693*
Y0070283*
Y0070229*
X0598639*
Y0070175*
Y0070121*
X0598585*
Y0070067*
X0598531*
Y0070013*
Y0069959*
X0598477*
Y0069905*
X0598423*
Y0069851*
X0598369*
Y0069797*
X0598315*
Y0069743*
X0598261*
Y0069688*
X0598207*
Y0069634*
X0598152*
Y006958*
X0598044*
Y0069526*
X059799*
Y0069472*
X0597882*
Y0069418*
X0597774*
Y0069364*
X0597666*
Y006931*
X0597504*
Y0069256*
X0597342*
Y0069202*
X0596423*
Y0069256*
X059626*
Y006931*
X0596098*
Y0069364*
X059599*
Y0069418*
X0595882*
Y0069472*
X0595774*
Y0069526*
X059572*
Y006958*
X0595666*
Y0069634*
X0595558*
Y0069688*
X0595504*
Y0069743*
X0595449*
Y0069797*
X0595395*
Y0069851*
X0595341*
Y0069905*
X0595287*
Y0069959*
Y0070013*
X0595233*
Y0070067*
X0595179*
Y0070121*
Y0070175*
X0595125*
Y0070229*
Y0070283*
X0595071*
Y0070337*
Y0070391*
X0595017*
Y0070445*
Y0070499*
X0594963*
Y0070553*
Y0070608*
Y0070662*
X0594909*
Y0070716*
Y007077*
Y0070824*
Y0070878*
Y0070932*
X0594855*
Y0070986*
Y007104*
Y0071094*
Y0071148*
Y0071202*
Y0071256*
Y007131*
Y0071364*
Y0071418*
Y0071473*
X0594909*
Y0071526*
Y0071581*
Y0071635*
Y0071689*
Y0071743*
X0594963*
Y0071797*
Y0071851*
Y0071905*
X0595017*
Y0071959*
Y0072013*
X0595071*
Y0072067*
Y0072121*
X0595125*
Y0072175*
Y0072229*
X0595179*
Y0072283*
Y0072338*
X0595233*
Y0072391*
X0595287*
Y0072446*
Y00725*
X0595341*
Y0072554*
X0595395*
Y0072608*
X0595449*
Y0072662*
X0595504*
Y0072716*
X0595558*
Y007277*
X0595612*
Y0072824*
X059572*
Y0072878*
X0595774*
Y0072932*
X0595882*
Y0072986*
X059599*
Y007304*
X0596098*
Y0073094*
X059626*
Y0073148*
X0596423*
Y0073203*
X0597342*
Y0073148*
G37*
G36*
X0589449Y0117695D02*
X0589989D01*
Y0117641*
X0590205*
Y0117587*
X0590422*
Y0117533*
X059053*
Y0117479*
X0590692*
Y0117425*
X05908*
Y0117371*
X0590908*
Y0117317*
X0591016*
Y0117263*
X0591124*
Y0117209*
X0591179*
Y0117155*
X0591287*
Y0117101*
X0591341*
Y0117047*
X0591395*
Y0116993*
X0591503*
Y0116939*
X0591557*
Y0116885*
X0591611*
Y0116831*
X0591665*
Y0116776*
X0591719*
Y0116722*
X0591773*
Y0116668*
X0591827*
Y0116614*
X0591881*
Y011656*
X0591935*
Y0116506*
Y0116452*
X059199*
Y0116398*
X0592043*
Y0116344*
X0592098*
Y011629*
Y0116236*
X0592152*
Y0116182*
X0592206*
Y0116128*
Y0116074*
X059226*
Y011602*
Y0115965*
X0592314*
Y0115911*
Y0115857*
X0592368*
Y0115803*
Y0115749*
X0592422*
Y0115695*
Y0115641*
Y0115587*
X0592476*
Y0115533*
Y0115479*
X059253*
Y0115425*
Y0115371*
Y0115317*
Y0115263*
X0592584*
Y0115209*
Y0115155*
Y0115101*
Y0115047*
Y0114992*
X0592638*
Y0114938*
Y0114884*
Y011483*
Y0114776*
Y0114722*
Y0114668*
Y0114614*
Y011456*
Y0114506*
Y0114452*
Y0114398*
Y0114344*
Y011429*
Y0114235*
Y0114181*
Y0114127*
Y0114073*
Y0114019*
Y0113965*
Y0113911*
Y0113857*
Y0113803*
Y0113749*
Y0113695*
Y0113641*
Y0113587*
Y0113533*
Y0113479*
Y0113425*
Y0113371*
Y0113317*
Y0113262*
Y0113208*
Y0113154*
Y01131*
Y0113046*
Y0112992*
Y0112938*
Y0112884*
Y011283*
Y0112776*
Y0112722*
Y0112668*
Y0112614*
Y011256*
Y0112505*
Y0112452*
Y0112397*
Y0112343*
Y0112289*
Y0112235*
Y0112181*
Y0112127*
Y0112073*
Y0112019*
Y0111965*
Y0111911*
Y0111857*
Y0111803*
Y0111749*
Y0111695*
Y0111641*
Y0111586*
Y0111532*
Y0111478*
Y0111424*
Y011137*
Y0111316*
Y0111262*
Y0111208*
Y0111154*
Y01111*
Y0111046*
Y0110992*
Y0110938*
Y0110884*
Y011083*
Y0110776*
Y0110722*
Y0110668*
Y0110613*
Y0110559*
Y0110505*
Y0110451*
Y0110397*
Y0110343*
Y0110289*
Y0110235*
Y0110181*
Y0110127*
Y0110073*
Y0110019*
Y0109965*
Y0109911*
Y0109856*
Y0109802*
Y0109748*
Y0109694*
Y010964*
Y0109586*
Y0109532*
Y0109478*
Y0109424*
Y010937*
Y0109316*
Y0109262*
Y0109208*
Y0109154*
Y01091*
Y0109046*
Y0108992*
Y0108938*
Y0108883*
Y0108829*
Y0108775*
Y0108721*
Y0108667*
Y0108613*
Y0108559*
Y0108505*
Y0108451*
Y0108397*
Y0108343*
Y0108289*
Y0108235*
Y0108181*
Y0108126*
Y0108072*
Y0108018*
Y0107964*
Y010791*
Y0107856*
Y0107802*
Y0107748*
Y0107694*
Y010764*
Y0107586*
Y0107532*
Y0107478*
Y0107424*
Y010737*
Y0107316*
Y0107262*
Y0107208*
Y0107153*
Y0107099*
Y0107045*
Y0106991*
Y0106937*
Y0106883*
Y0106829*
Y0106775*
Y0106721*
Y0106667*
Y0106613*
Y0106559*
Y0106505*
Y0106451*
Y0106397*
Y0106342*
Y0106288*
Y0106234*
Y010618*
Y0106126*
Y0106072*
Y0106018*
Y0105964*
Y010591*
Y0105856*
Y0105802*
Y0105748*
Y0105694*
Y010564*
Y0105586*
Y0105532*
Y0105477*
Y0105423*
Y0105369*
Y0105315*
Y0105261*
Y0105207*
Y0105153*
Y0105099*
Y0105045*
Y0104991*
Y0104937*
Y0104883*
Y0104829*
Y0104775*
Y0104721*
Y0104667*
Y0104613*
Y0104558*
Y0104504*
Y010445*
Y0104396*
Y0104342*
Y0104288*
Y0104234*
Y010418*
Y0104126*
Y0104072*
Y0104018*
Y0103964*
Y010391*
Y0103856*
Y0103802*
Y0103747*
Y0103693*
Y0103639*
Y0103585*
Y0103531*
Y0103477*
Y0103423*
Y0103369*
Y0103315*
Y0103261*
Y0103207*
Y0103153*
Y0103099*
Y0103045*
Y0102991*
Y0102937*
Y0102883*
Y0102828*
Y0102774*
Y010272*
Y0102666*
Y0102612*
Y0102558*
Y0102504*
Y010245*
Y0102396*
Y0102342*
Y0102288*
Y0102234*
Y010218*
Y0102126*
Y0102072*
Y0102017*
Y0101963*
Y0101909*
Y0101855*
Y0101801*
Y0101747*
Y0101693*
Y0101639*
Y0101585*
Y0101531*
Y0101477*
Y0101423*
Y0101369*
Y0101315*
Y0101261*
Y0101207*
Y0101153*
Y0101099*
Y0101044*
Y010099*
Y0100936*
Y0100882*
Y0100828*
Y0100774*
Y010072*
Y0100666*
Y0100612*
Y0100558*
Y0100504*
Y010045*
Y0100396*
Y0100342*
Y0100287*
Y0100233*
Y0100179*
Y0100125*
Y0100071*
Y0100017*
Y0099963*
Y0099909*
Y0099855*
Y0099801*
Y0099747*
Y0099693*
Y0099639*
Y0099585*
Y0099531*
Y0099477*
Y0099423*
Y0099369*
Y0099314*
Y009926*
Y0099206*
Y0099152*
Y0099098*
Y0099044*
Y009899*
Y0098936*
Y0098882*
Y0098828*
Y0098774*
Y009872*
Y0098666*
Y0098612*
Y0098558*
Y0098504*
Y0098449*
Y0098395*
Y0098341*
Y0098287*
Y0098233*
Y0098179*
Y0098125*
Y0098071*
Y0098017*
Y0097963*
Y0097909*
Y0097855*
Y0097801*
Y0097747*
Y0097693*
Y0097638*
Y0097584*
Y009753*
Y0097476*
Y0097422*
Y0097368*
Y0097314*
Y009726*
Y0097206*
Y0097152*
Y0097098*
Y0097044*
Y009699*
Y0096936*
Y0096882*
Y0096828*
Y0096773*
Y0096719*
Y0096665*
Y0096611*
Y0096557*
Y0096503*
Y0096449*
Y0096395*
Y0096341*
Y0096287*
Y0096233*
Y0096179*
Y0096125*
Y0096071*
Y0096017*
Y0095963*
Y0095908*
Y0095854*
Y00958*
Y0095746*
Y0095692*
Y0095638*
Y0095584*
Y009553*
Y0095476*
Y0095422*
Y0095368*
Y0095314*
Y009526*
Y0095206*
Y0095152*
Y0095098*
Y0095043*
Y009499*
Y0094935*
Y0094881*
Y0094827*
Y0094773*
Y0094719*
Y0094665*
Y0094611*
Y0094557*
Y0094503*
Y0094449*
Y0094395*
Y0094341*
Y0094287*
Y0094233*
Y0094178*
Y0094125*
Y009407*
Y0094016*
Y0093962*
Y0093908*
Y0093854*
Y00938*
Y0093746*
Y0093692*
Y0093638*
Y0093584*
Y009353*
Y0093476*
Y0093422*
Y0093368*
Y0093313*
Y009326*
Y0093205*
Y0093151*
Y0093097*
Y0093043*
Y0092989*
Y0092935*
Y0092881*
Y0092827*
Y0092773*
Y0092719*
Y0092665*
Y0092611*
Y0092557*
Y0092503*
Y0092449*
Y0092395*
Y009234*
Y0092286*
Y0092232*
Y0092178*
Y0092124*
Y009207*
Y0092016*
Y0091962*
Y0091908*
Y0091854*
Y00918*
Y0091746*
Y0091692*
Y0091638*
Y0091584*
Y009153*
Y0091475*
Y0091421*
Y0091367*
Y0091313*
Y0091259*
Y0091205*
Y0091151*
Y0091097*
Y0091043*
Y0090989*
Y0090935*
Y0090881*
Y0090827*
Y0090773*
Y0090719*
Y0090664*
Y009061*
Y0090556*
Y0090502*
Y0090448*
Y0090394*
Y009034*
Y0090286*
Y0090232*
Y0090178*
Y0090124*
Y009007*
Y0090016*
Y0089962*
Y0089908*
Y0089854*
Y0089799*
Y0089745*
Y0089691*
Y0089637*
Y0089583*
Y0089529*
Y0089475*
Y0089421*
Y0089367*
Y0089313*
Y0089259*
Y0089205*
Y0089151*
Y0089097*
Y0089043*
Y0088989*
Y0088934*
Y008888*
Y0088826*
Y0088772*
Y0088718*
Y0088664*
Y008861*
Y0088556*
Y0088502*
Y0088448*
Y0088394*
Y008834*
Y0088286*
Y0088232*
Y0088178*
Y0088124*
Y0088069*
Y0088016*
Y0087961*
Y0087907*
Y0087853*
Y0087799*
Y0087745*
Y0087691*
Y0087637*
Y0087583*
Y0087529*
Y0087475*
Y0087421*
Y0087367*
Y0087313*
Y0087259*
Y0087204*
Y0087151*
Y0087096*
Y0087042*
Y0086988*
Y0086934*
Y008688*
Y0086826*
Y0086772*
Y0086718*
Y0086664*
Y008661*
Y0086556*
Y0086502*
Y0086448*
Y0086394*
Y0086339*
Y0086286*
Y0086231*
Y0086177*
Y0086123*
Y0086069*
Y0086015*
Y0085961*
Y0085907*
Y0085853*
Y0085799*
Y0085745*
Y0085691*
Y0085637*
Y0085583*
Y0085529*
Y0085474*
Y0085421*
Y0085366*
Y0085312*
Y0085258*
Y0085204*
Y008515*
Y0085096*
Y0085042*
Y0084988*
Y0084934*
Y008488*
Y0084826*
Y0084772*
Y0084718*
Y0084664*
Y008461*
Y0084556*
Y0084501*
Y0084447*
Y0084393*
Y0084339*
Y0084285*
Y0084231*
Y0084177*
Y0084123*
Y0084069*
Y0084015*
Y0083961*
Y0083907*
Y0083853*
Y0083799*
Y0083745*
Y0083691*
Y0083636*
Y0083582*
Y0083528*
Y0083474*
Y008342*
Y0083366*
Y0083312*
Y0083258*
Y0083204*
Y008315*
Y0083096*
Y0083042*
Y0082988*
Y0082934*
Y008288*
Y0082825*
Y0082771*
Y0082717*
Y0082663*
Y0082609*
Y0082555*
Y0082501*
Y0082447*
Y0082393*
Y0082339*
Y0082285*
Y0082231*
Y0082177*
Y0082123*
Y0082069*
Y0082015*
Y008196*
Y0081906*
Y0081852*
Y0081798*
Y0081744*
Y008169*
Y0081636*
Y0081582*
Y0081528*
Y0081474*
Y008142*
Y0081366*
Y0081312*
Y0081258*
Y0081204*
Y008115*
Y0081095*
Y0081042*
Y0080987*
Y0080933*
Y0080879*
Y0080825*
Y0080771*
Y0080717*
Y0080663*
Y0080609*
Y0080555*
Y0080501*
Y0080447*
Y0080393*
Y0080339*
Y0080285*
Y008023*
Y0080177*
Y0080122*
Y0080068*
Y0080014*
Y007996*
Y0079906*
Y0079852*
Y0079798*
Y0079744*
Y007969*
Y0079636*
Y0079582*
Y0079528*
Y0079474*
Y007942*
Y0079365*
Y0079312*
Y0079257*
Y0079203*
Y0079149*
Y0079095*
Y0079041*
Y0078987*
Y0078933*
Y0078879*
Y0078825*
Y0078771*
Y0078717*
Y0078663*
Y0078609*
Y0078555*
Y00785*
Y0078447*
Y0078392*
Y0078338*
Y0078284*
Y007823*
Y0078176*
Y0078122*
Y0078068*
Y0078014*
Y007796*
Y0077906*
Y0077852*
Y0077798*
Y0077744*
Y007769*
Y0077636*
Y0077582*
Y0077527*
Y0077473*
Y0077419*
Y0077365*
Y0077311*
Y0077257*
Y0077203*
Y0077149*
Y0077095*
Y0077041*
Y0076987*
Y0076933*
Y0076879*
Y0076825*
Y0076771*
Y0076717*
Y0076662*
Y0076608*
Y0076554*
Y00765*
Y0076446*
Y0076392*
Y0076338*
Y0076284*
Y007623*
Y0076176*
Y0076122*
Y0076068*
Y0076014*
Y007596*
Y0075906*
Y0075852*
Y0075797*
Y0075743*
Y0075689*
Y0075635*
Y0075581*
Y0075527*
Y0075473*
Y0075419*
Y0075365*
Y0075311*
Y0075257*
Y0075203*
Y0075149*
Y0075095*
Y0075041*
Y0074986*
Y0074932*
Y0074878*
Y0074824*
Y007477*
Y0074716*
Y0074662*
Y0074608*
Y0074554*
Y00745*
Y0074446*
Y0074392*
Y0074338*
Y0074284*
Y007423*
Y0074176*
Y0074121*
Y0074067*
Y0074013*
Y0073959*
Y0073905*
Y0073851*
Y0073797*
Y0073743*
Y0073689*
Y0073635*
Y0073581*
Y0073527*
Y0073473*
Y0073419*
Y0073365*
Y0073311*
Y0073256*
Y0073203*
Y0073148*
Y0073094*
Y007304*
Y0072986*
Y0072932*
Y0072878*
Y0072824*
Y007277*
Y0072716*
Y0072662*
Y0072608*
Y0072554*
Y00725*
Y0072446*
Y0072391*
Y0072338*
Y0072283*
Y0072229*
Y0072175*
Y0072121*
Y0072067*
Y0072013*
Y0071959*
Y0071905*
Y0071851*
Y0071797*
Y0071743*
Y0071689*
Y0071635*
Y0071581*
Y0071526*
Y0071473*
Y0071418*
Y0071364*
Y007131*
Y0071256*
Y0071202*
Y0071148*
Y0071094*
Y007104*
Y0070986*
Y0070932*
Y0070878*
Y0070824*
Y007077*
Y0070716*
Y0070662*
Y0070608*
Y0070553*
Y0070499*
Y0070445*
Y0070391*
Y0070337*
Y0070283*
Y0070229*
Y0070175*
Y0070121*
Y0070067*
Y0070013*
Y0069959*
Y0069905*
Y0069851*
Y0069797*
Y0069743*
Y0069688*
Y0069634*
Y006958*
Y0069526*
Y0069472*
Y0069418*
Y0069364*
Y006931*
Y0069256*
Y0069202*
Y0069148*
Y0069094*
Y006904*
Y0068986*
Y0068932*
Y0068878*
Y0068823*
Y0068769*
Y0068715*
Y0068661*
Y0068607*
Y0068553*
Y0068499*
Y0068445*
Y0068391*
Y0068337*
Y0068283*
Y0068229*
Y0068175*
Y0068121*
Y0068067*
Y0068012*
Y0067958*
Y0067904*
Y006785*
Y0067796*
Y0067742*
Y0067688*
Y0067634*
Y006758*
Y0067526*
Y0067472*
Y0067418*
Y0067364*
Y006731*
Y0067256*
Y0067202*
Y0067147*
Y0067093*
Y0067039*
Y0066985*
Y0066931*
Y0066877*
Y0066823*
Y0066769*
Y0066715*
Y0066661*
Y0066607*
Y0066553*
Y0066499*
Y0066445*
Y0066391*
Y0066337*
Y0066282*
Y0066228*
Y0066174*
Y006612*
Y0066066*
Y0066012*
Y0065958*
Y0065904*
Y006585*
Y0065796*
Y0065742*
Y0065688*
Y0065634*
Y006558*
Y0065526*
Y0065472*
Y0065417*
Y0065364*
Y0065309*
Y0065255*
Y0065201*
Y0065147*
Y0065093*
Y0065039*
Y0064985*
Y0064931*
Y0064877*
Y0064823*
Y0064769*
Y0064715*
Y0064661*
Y0064607*
Y0064552*
Y0064499*
Y0064444*
Y006439*
Y0064336*
Y0064282*
Y0064228*
Y0064174*
Y006412*
Y0064066*
Y0064012*
Y0063958*
Y0063904*
Y006385*
Y0063796*
Y0063742*
Y0063688*
Y0063634*
Y0063579*
Y0063525*
Y0063471*
Y0063417*
Y0063363*
Y0063309*
Y0063255*
Y0063201*
Y0063147*
Y0063093*
Y0063039*
Y0062985*
Y0062931*
Y0062877*
Y0062823*
Y0062769*
Y0062714*
Y006266*
Y0062606*
Y0062552*
Y0062498*
Y0062444*
Y006239*
Y0062336*
Y0062282*
Y0062228*
Y0062174*
Y006212*
Y0062066*
Y0062012*
Y0061958*
Y0061904*
Y0061849*
Y0061795*
Y0061741*
Y0061687*
Y0061633*
Y0061579*
Y0061525*
Y0061471*
Y0061417*
Y0061363*
Y0061309*
Y0061255*
Y0061201*
Y0061147*
Y0061093*
Y0061039*
Y0060984*
Y006093*
Y0060876*
Y0060822*
Y0060768*
Y0060714*
Y006066*
Y0060606*
Y0060552*
Y0060498*
Y0060444*
Y006039*
Y0060336*
Y0060282*
Y0060228*
Y0060173*
Y0060119*
Y0060065*
Y0060011*
Y0059957*
Y0059903*
Y0059849*
Y0059795*
Y0059741*
Y0059687*
Y0059633*
Y0059579*
Y0059525*
Y0059471*
Y0059417*
Y0059363*
Y0059308*
Y0059254*
Y00592*
Y0059146*
Y0059092*
Y0059038*
Y0058984*
Y005893*
Y0058876*
Y0058822*
Y0058768*
Y0058714*
Y005866*
Y0058606*
Y0058552*
Y0058498*
Y0058443*
Y005839*
Y0058335*
Y0058281*
Y0058227*
Y0058173*
Y0058119*
Y0058065*
Y0058011*
Y0057957*
Y0057903*
Y0057849*
Y0057795*
Y0057741*
Y0057687*
Y0057633*
Y0057578*
Y0057525*
Y005747*
Y0057416*
Y0057362*
Y0057308*
Y0057254*
Y00572*
Y0057146*
Y0057092*
Y0057038*
Y0056984*
Y005693*
Y0056876*
Y0056822*
Y0056768*
Y0056714*
Y005666*
Y0056605*
Y0056551*
Y0056497*
Y0056443*
Y0056389*
Y0056335*
Y0056281*
Y0056227*
Y0056173*
Y0056119*
Y0056065*
Y0056011*
Y0055957*
X0590638*
Y0056011*
Y0056065*
Y0056119*
Y0056173*
Y0056227*
Y0056281*
Y0056335*
Y0056389*
Y0056443*
Y0056497*
Y0056551*
Y0056605*
Y005666*
Y0056714*
Y0056768*
Y0056822*
Y0056876*
Y005693*
Y0056984*
Y0057038*
Y0057092*
Y0057146*
Y00572*
Y0057254*
Y0057308*
Y0057362*
Y0057416*
Y005747*
Y0057525*
Y0057578*
Y0057633*
Y0057687*
Y0057741*
Y0057795*
Y0057849*
Y0057903*
Y0057957*
Y0058011*
Y0058065*
Y0058119*
Y0058173*
Y0058227*
Y0058281*
Y0058335*
Y005839*
Y0058443*
Y0058498*
Y0058552*
Y0058606*
Y005866*
Y0058714*
Y0058768*
Y0058822*
Y0058876*
Y005893*
Y0058984*
Y0059038*
Y0059092*
Y0059146*
Y00592*
Y0059254*
Y0059308*
Y0059363*
Y0059417*
Y0059471*
Y0059525*
Y0059579*
Y0059633*
Y0059687*
Y0059741*
Y0059795*
Y0059849*
Y0059903*
Y0059957*
Y0060011*
Y0060065*
Y0060119*
Y0060173*
Y0060228*
Y0060282*
Y0060336*
Y006039*
Y0060444*
Y0060498*
Y0060552*
Y0060606*
Y006066*
Y0060714*
Y0060768*
Y0060822*
Y0060876*
Y006093*
Y0060984*
Y0061039*
Y0061093*
Y0061147*
Y0061201*
Y0061255*
Y0061309*
Y0061363*
Y0061417*
Y0061471*
Y0061525*
Y0061579*
Y0061633*
Y0061687*
Y0061741*
Y0061795*
Y0061849*
Y0061904*
Y0061958*
Y0062012*
Y0062066*
Y006212*
Y0062174*
Y0062228*
Y0062282*
Y0062336*
Y006239*
Y0062444*
Y0062498*
Y0062552*
Y0062606*
Y006266*
Y0062714*
Y0062769*
Y0062823*
Y0062877*
Y0062931*
Y0062985*
Y0063039*
Y0063093*
Y0063147*
Y0063201*
Y0063255*
Y0063309*
Y0063363*
Y0063417*
Y0063471*
Y0063525*
Y0063579*
Y0063634*
Y0063688*
Y0063742*
Y0063796*
Y006385*
Y0063904*
Y0063958*
Y0064012*
Y0064066*
Y006412*
Y0064174*
Y0064228*
Y0064282*
Y0064336*
Y006439*
Y0064444*
Y0064499*
Y0064552*
Y0064607*
Y0064661*
Y0064715*
Y0064769*
Y0064823*
Y0064877*
Y0064931*
Y0064985*
Y0065039*
Y0065093*
Y0065147*
Y0065201*
Y0065255*
Y0065309*
Y0065364*
Y0065417*
Y0065472*
Y0065526*
Y006558*
Y0065634*
Y0065688*
Y0065742*
Y0065796*
Y006585*
Y0065904*
Y0065958*
Y0066012*
Y0066066*
Y006612*
Y0066174*
Y0066228*
Y0066282*
Y0066337*
Y0066391*
Y0066445*
Y0066499*
Y0066553*
Y0066607*
Y0066661*
Y0066715*
Y0066769*
Y0066823*
Y0066877*
Y0066931*
Y0066985*
Y0067039*
Y0067093*
Y0067147*
Y0067202*
Y0067256*
Y006731*
Y0067364*
Y0067418*
Y0067472*
Y0067526*
Y006758*
Y0067634*
Y0067688*
Y0067742*
Y0067796*
Y006785*
Y0067904*
Y0067958*
Y0068012*
Y0068067*
Y0068121*
Y0068175*
Y0068229*
Y0068283*
Y0068337*
Y0068391*
Y0068445*
Y0068499*
Y0068553*
Y0068607*
Y0068661*
Y0068715*
Y0068769*
Y0068823*
Y0068878*
Y0068932*
Y0068986*
Y006904*
Y0069094*
Y0069148*
Y0069202*
Y0069256*
Y006931*
Y0069364*
Y0069418*
Y0069472*
Y0069526*
Y006958*
Y0069634*
Y0069688*
Y0069743*
Y0069797*
Y0069851*
Y0069905*
Y0069959*
Y0070013*
Y0070067*
Y0070121*
Y0070175*
Y0070229*
Y0070283*
Y0070337*
Y0070391*
Y0070445*
Y0070499*
Y0070553*
Y0070608*
Y0070662*
Y0070716*
Y007077*
Y0070824*
Y0070878*
Y0070932*
Y0070986*
Y007104*
Y0071094*
Y0071148*
Y0071202*
Y0071256*
Y007131*
Y0071364*
Y0071418*
Y0071473*
Y0071526*
Y0071581*
Y0071635*
Y0071689*
Y0071743*
Y0071797*
Y0071851*
Y0071905*
Y0071959*
Y0072013*
Y0072067*
Y0072121*
Y0072175*
Y0072229*
Y0072283*
Y0072338*
Y0072391*
Y0072446*
Y00725*
Y0072554*
Y0072608*
Y0072662*
Y0072716*
Y007277*
Y0072824*
Y0072878*
Y0072932*
Y0072986*
Y007304*
Y0073094*
Y0073148*
Y0073203*
Y0073256*
Y0073311*
Y0073365*
Y0073419*
Y0073473*
Y0073527*
Y0073581*
Y0073635*
Y0073689*
Y0073743*
Y0073797*
Y0073851*
Y0073905*
Y0073959*
Y0074013*
Y0074067*
Y0074121*
Y0074176*
Y007423*
Y0074284*
Y0074338*
Y0074392*
Y0074446*
Y00745*
Y0074554*
Y0074608*
Y0074662*
Y0074716*
Y007477*
Y0074824*
Y0074878*
Y0074932*
Y0074986*
Y0075041*
Y0075095*
Y0075149*
Y0075203*
Y0075257*
Y0075311*
Y0075365*
Y0075419*
Y0075473*
Y0075527*
Y0075581*
Y0075635*
Y0075689*
Y0075743*
Y0075797*
Y0075852*
Y0075906*
Y007596*
Y0076014*
Y0076068*
Y0076122*
Y0076176*
Y007623*
Y0076284*
Y0076338*
Y0076392*
Y0076446*
Y00765*
Y0076554*
Y0076608*
Y0076662*
Y0076717*
Y0076771*
Y0076825*
Y0076879*
Y0076933*
Y0076987*
Y0077041*
Y0077095*
Y0077149*
Y0077203*
Y0077257*
Y0077311*
Y0077365*
Y0077419*
Y0077473*
Y0077527*
Y0077582*
Y0077636*
Y007769*
Y0077744*
Y0077798*
Y0077852*
Y0077906*
Y007796*
Y0078014*
Y0078068*
Y0078122*
Y0078176*
Y007823*
Y0078284*
Y0078338*
Y0078392*
Y0078447*
Y00785*
Y0078555*
Y0078609*
Y0078663*
Y0078717*
Y0078771*
Y0078825*
Y0078879*
Y0078933*
Y0078987*
Y0079041*
Y0079095*
Y0079149*
Y0079203*
Y0079257*
Y0079312*
Y0079365*
Y007942*
Y0079474*
Y0079528*
Y0079582*
Y0079636*
Y007969*
Y0079744*
Y0079798*
Y0079852*
Y0079906*
Y007996*
Y0080014*
Y0080068*
Y0080122*
Y0080177*
Y008023*
Y0080285*
Y0080339*
Y0080393*
Y0080447*
Y0080501*
Y0080555*
Y0080609*
Y0080663*
Y0080717*
Y0080771*
Y0080825*
Y0080879*
Y0080933*
Y0080987*
Y0081042*
Y0081095*
Y008115*
Y0081204*
Y0081258*
Y0081312*
Y0081366*
Y008142*
Y0081474*
Y0081528*
Y0081582*
Y0081636*
Y008169*
Y0081744*
Y0081798*
Y0081852*
Y0081906*
Y008196*
Y0082015*
Y0082069*
Y0082123*
Y0082177*
Y0082231*
Y0082285*
Y0082339*
Y0082393*
Y0082447*
Y0082501*
Y0082555*
Y0082609*
Y0082663*
Y0082717*
Y0082771*
Y0082825*
Y008288*
Y0082934*
Y0082988*
Y0083042*
Y0083096*
Y008315*
Y0083204*
Y0083258*
Y0083312*
Y0083366*
Y008342*
Y0083474*
Y0083528*
Y0083582*
Y0083636*
Y0083691*
Y0083745*
Y0083799*
Y0083853*
Y0083907*
Y0083961*
Y0084015*
Y0084069*
Y0084123*
Y0084177*
Y0084231*
Y0084285*
Y0084339*
Y0084393*
Y0084447*
Y0084501*
Y0084556*
Y008461*
Y0084664*
Y0084718*
Y0084772*
Y0084826*
Y008488*
Y0084934*
Y0084988*
Y0085042*
Y0085096*
Y008515*
Y0085204*
Y0085258*
Y0085312*
Y0085366*
Y0085421*
Y0085474*
Y0085529*
Y0085583*
Y0085637*
Y0085691*
Y0085745*
Y0085799*
Y0085853*
Y0085907*
Y0085961*
Y0086015*
Y0086069*
Y0086123*
Y0086177*
Y0086231*
Y0086286*
Y0086339*
Y0086394*
Y0086448*
Y0086502*
Y0086556*
Y008661*
Y0086664*
Y0086718*
Y0086772*
Y0086826*
Y008688*
Y0086934*
Y0086988*
Y0087042*
Y0087096*
Y0087151*
Y0087204*
Y0087259*
Y0087313*
Y0087367*
Y0087421*
Y0087475*
Y0087529*
Y0087583*
Y0087637*
Y0087691*
Y0087745*
Y0087799*
Y0087853*
Y0087907*
Y0087961*
Y0088016*
Y0088069*
Y0088124*
Y0088178*
Y0088232*
Y0088286*
Y008834*
Y0088394*
Y0088448*
Y0088502*
Y0088556*
Y008861*
Y0088664*
Y0088718*
Y0088772*
Y0088826*
Y008888*
Y0088934*
Y0088989*
Y0089043*
Y0089097*
Y0089151*
Y0089205*
Y0089259*
Y0089313*
Y0089367*
Y0089421*
Y0089475*
Y0089529*
Y0089583*
Y0089637*
Y0089691*
Y0089745*
Y0089799*
Y0089854*
Y0089908*
Y0089962*
Y0090016*
Y009007*
Y0090124*
Y0090178*
Y0090232*
Y0090286*
Y009034*
Y0090394*
Y0090448*
Y0090502*
Y0090556*
Y009061*
Y0090664*
Y0090719*
Y0090773*
Y0090827*
Y0090881*
Y0090935*
Y0090989*
Y0091043*
Y0091097*
Y0091151*
Y0091205*
Y0091259*
Y0091313*
Y0091367*
Y0091421*
Y0091475*
Y009153*
Y0091584*
Y0091638*
Y0091692*
Y0091746*
Y00918*
Y0091854*
Y0091908*
Y0091962*
Y0092016*
Y009207*
Y0092124*
Y0092178*
Y0092232*
Y0092286*
Y009234*
Y0092395*
Y0092449*
Y0092503*
Y0092557*
Y0092611*
Y0092665*
Y0092719*
Y0092773*
Y0092827*
Y0092881*
Y0092935*
Y0092989*
Y0093043*
Y0093097*
Y0093151*
Y0093205*
Y009326*
Y0093313*
Y0093368*
Y0093422*
Y0093476*
Y009353*
Y0093584*
Y0093638*
Y0093692*
Y0093746*
Y00938*
Y0093854*
Y0093908*
Y0093962*
Y0094016*
Y009407*
Y0094125*
Y0094178*
Y0094233*
Y0094287*
Y0094341*
Y0094395*
Y0094449*
Y0094503*
Y0094557*
Y0094611*
Y0094665*
Y0094719*
Y0094773*
Y0094827*
Y0094881*
Y0094935*
Y009499*
Y0095043*
Y0095098*
Y0095152*
Y0095206*
Y009526*
Y0095314*
Y0095368*
Y0095422*
Y0095476*
Y009553*
Y0095584*
Y0095638*
Y0095692*
Y0095746*
Y00958*
Y0095854*
Y0095908*
Y0095963*
Y0096017*
Y0096071*
Y0096125*
Y0096179*
Y0096233*
Y0096287*
Y0096341*
Y0096395*
Y0096449*
Y0096503*
Y0096557*
Y0096611*
Y0096665*
Y0096719*
Y0096773*
Y0096828*
Y0096882*
Y0096936*
Y009699*
Y0097044*
Y0097098*
Y0097152*
Y0097206*
Y009726*
Y0097314*
Y0097368*
Y0097422*
Y0097476*
Y009753*
Y0097584*
Y0097638*
Y0097693*
Y0097747*
Y0097801*
Y0097855*
Y0097909*
Y0097963*
Y0098017*
Y0098071*
Y0098125*
Y0098179*
Y0098233*
Y0098287*
Y0098341*
Y0098395*
Y0098449*
Y0098504*
Y0098558*
Y0098612*
Y0098666*
Y009872*
Y0098774*
Y0098828*
Y0098882*
Y0098936*
Y009899*
Y0099044*
Y0099098*
Y0099152*
Y0099206*
Y009926*
Y0099314*
Y0099369*
Y0099423*
Y0099477*
Y0099531*
Y0099585*
Y0099639*
Y0099693*
Y0099747*
Y0099801*
Y0099855*
Y0099909*
Y0099963*
Y0100017*
Y0100071*
Y0100125*
Y0100179*
Y0100233*
Y0100287*
Y0100342*
Y0100396*
Y010045*
Y0100504*
Y0100558*
Y0100612*
Y0100666*
Y010072*
Y0100774*
Y0100828*
Y0100882*
Y0100936*
Y010099*
Y0101044*
Y0101099*
Y0101153*
Y0101207*
Y0101261*
Y0101315*
Y0101369*
Y0101423*
Y0101477*
Y0101531*
Y0101585*
Y0101639*
Y0101693*
Y0101747*
Y0101801*
Y0101855*
Y0101909*
Y0101963*
Y0102017*
Y0102072*
Y0102126*
Y010218*
Y0102234*
Y0102288*
Y0102342*
Y0102396*
Y010245*
Y0102504*
Y0102558*
Y0102612*
Y0102666*
Y010272*
Y0102774*
Y0102828*
Y0102883*
Y0102937*
Y0102991*
Y0103045*
Y0103099*
Y0103153*
Y0103207*
Y0103261*
Y0103315*
Y0103369*
Y0103423*
Y0103477*
Y0103531*
Y0103585*
Y0103639*
Y0103693*
Y0103747*
Y0103802*
Y0103856*
Y010391*
Y0103964*
Y0104018*
Y0104072*
Y0104126*
Y010418*
Y0104234*
Y0104288*
Y0104342*
Y0104396*
Y010445*
Y0104504*
Y0104558*
Y0104613*
Y0104667*
Y0104721*
Y0104775*
Y0104829*
Y0104883*
Y0104937*
Y0104991*
Y0105045*
Y0105099*
Y0105153*
Y0105207*
Y0105261*
Y0105315*
Y0105369*
Y0105423*
Y0105477*
Y0105532*
Y0105586*
Y010564*
Y0105694*
Y0105748*
Y0105802*
Y0105856*
Y010591*
Y0105964*
Y0106018*
Y0106072*
Y0106126*
Y010618*
Y0106234*
Y0106288*
Y0106342*
Y0106397*
Y0106451*
Y0106505*
Y0106559*
Y0106613*
Y0106667*
Y0106721*
Y0106775*
Y0106829*
Y0106883*
Y0106937*
Y0106991*
Y0107045*
Y0107099*
Y0107153*
Y0107208*
Y0107262*
Y0107316*
Y010737*
Y0107424*
Y0107478*
Y0107532*
Y0107586*
Y010764*
Y0107694*
Y0107748*
Y0107802*
Y0107856*
Y010791*
Y0107964*
Y0108018*
Y0108072*
Y0108126*
Y0108181*
Y0108235*
Y0108289*
Y0108343*
Y0108397*
Y0108451*
Y0108505*
Y0108559*
Y0108613*
Y0108667*
Y0108721*
Y0108775*
Y0108829*
Y0108883*
Y0108938*
Y0108992*
Y0109046*
Y01091*
Y0109154*
Y0109208*
Y0109262*
Y0109316*
Y010937*
Y0109424*
Y0109478*
Y0109532*
Y0109586*
Y010964*
Y0109694*
Y0109748*
Y0109802*
Y0109856*
Y0109911*
Y0109965*
Y0110019*
Y0110073*
Y0110127*
Y0110181*
Y0110235*
Y0110289*
Y0110343*
Y0110397*
Y0110451*
Y0110505*
Y0110559*
Y0110613*
Y0110668*
Y0110722*
Y0110776*
Y011083*
Y0110884*
Y0110938*
Y0110992*
Y0111046*
Y01111*
Y0111154*
Y0111208*
Y0111262*
Y0111316*
Y011137*
Y0111424*
Y0111478*
Y0111532*
Y0111586*
Y0111641*
Y0111695*
Y0111749*
Y0111803*
Y0111857*
Y0111911*
Y0111965*
Y0112019*
Y0112073*
Y0112127*
Y0112181*
Y0112235*
Y0112289*
Y0112343*
Y0112397*
Y0112452*
Y0112505*
Y011256*
Y0112614*
Y0112668*
Y0112722*
Y0112776*
Y011283*
Y0112884*
Y0112938*
Y0112992*
Y0113046*
Y01131*
Y0113154*
Y0113208*
Y0113262*
Y0113317*
Y0113371*
Y0113425*
Y0113479*
Y0113533*
Y0113587*
Y0113641*
Y0113695*
Y0113749*
Y0113803*
Y0113857*
Y0113911*
Y0113965*
Y0114019*
Y0114073*
Y0114127*
Y0114181*
Y0114235*
Y011429*
Y0114344*
Y0114398*
Y0114452*
X0590584*
Y0114506*
Y011456*
Y0114614*
Y0114668*
Y0114722*
X059053*
Y0114776*
Y011483*
X0590476*
Y0114884*
Y0114938*
X0590422*
Y0114992*
Y0115047*
X0590368*
Y0115101*
X0590314*
Y0115155*
Y0115209*
X059026*
Y0115263*
X0590205*
Y0115317*
X0590151*
Y0115371*
X0590043*
Y0115425*
X0589989*
Y0115479*
X0589881*
Y0115533*
X0589773*
Y0115587*
X0589665*
Y0115641*
X0589449*
Y0115695*
X0582583*
Y0115749*
Y0115803*
Y0115857*
Y0115911*
Y0115965*
Y011602*
Y0116074*
Y0116128*
Y0116182*
Y0116236*
Y011629*
Y0116344*
Y0116398*
Y0116452*
Y0116506*
Y011656*
Y0116614*
Y0116668*
Y0116722*
Y0116776*
Y0116831*
Y0116885*
Y0116939*
Y0116993*
Y0117047*
Y0117101*
Y0117155*
Y0117209*
Y0117263*
Y0117317*
Y0117371*
Y0117425*
Y0117479*
Y0117533*
Y0117587*
Y0117641*
Y0117695*
Y011775*
X0589449*
Y0117695*
G37*
%LNtimecard-dc-beta-v1-2*%
%LPC*%
G36*
X0639186Y0104558D02*
X0639023D01*
Y0104504*
X0638969*
Y0104558*
X0632644*
Y0104504*
X0632374*
Y010445*
X0632212*
Y0104396*
X0632103*
Y0104342*
X0632049*
Y0104288*
X0631995*
Y0104234*
X0631941*
Y010418*
X0631887*
Y0104126*
X0631833*
Y0104072*
X0631779*
Y0104018*
X0631725*
Y0103964*
X0631671*
Y010391*
X0631617*
Y0103856*
X0631563*
Y0103802*
X0631509*
Y0103747*
X0631455*
Y0103693*
X0631401*
Y0103639*
X0631347*
Y0103585*
X0631293*
Y0103531*
X0631239*
Y0103477*
X0631184*
Y0103423*
X063113*
Y0103369*
X0631076*
Y0103315*
X0631022*
Y0103261*
X0630968*
Y0103207*
X0630914*
Y0103153*
X063086*
Y0103099*
X0630806*
Y0103045*
X0630752*
Y0102991*
X0630698*
Y0102937*
X0630644*
Y0102883*
X063059*
Y0102828*
X0630536*
Y0102774*
Y010272*
Y0102666*
X0630482*
Y0102612*
Y0102558*
Y0102504*
Y010245*
Y0102396*
X0630428*
Y0102342*
Y0102288*
Y0102234*
Y010218*
Y0102126*
Y0102072*
Y0102017*
Y0101963*
Y0101909*
Y0101855*
Y0101801*
Y0101747*
Y0101693*
Y0101639*
Y0101585*
Y0101531*
Y0101477*
Y0101423*
Y0101369*
Y0101315*
Y0101261*
Y0101207*
Y0101153*
Y0101099*
Y0101044*
Y010099*
Y0100936*
Y0100882*
Y0100828*
Y0100774*
Y010072*
Y0100666*
Y0100612*
Y0100558*
Y0100504*
Y010045*
Y0100396*
Y0100342*
Y0100287*
Y0100233*
Y0100179*
Y0100125*
Y0100071*
Y0100017*
Y0099963*
Y0099909*
Y0099855*
Y0099801*
Y0099747*
Y0099693*
Y0099639*
Y0099585*
Y0099531*
Y0099477*
Y0099423*
Y0099369*
Y0099314*
Y009926*
Y0099206*
Y0099152*
Y0099098*
Y0099044*
Y009899*
Y0098936*
Y0098882*
Y0098828*
Y0098774*
Y009872*
Y0098666*
Y0098612*
Y0098558*
Y0098504*
Y0098449*
Y0098395*
Y0098341*
Y0098287*
Y0098233*
Y0098179*
Y0098125*
Y0098071*
Y0098017*
Y0097963*
Y0097909*
Y0097855*
Y0097801*
Y0097747*
Y0097693*
Y0097638*
Y0097584*
Y009753*
Y0097476*
Y0097422*
Y0097368*
Y0097314*
Y009726*
Y0097206*
Y0097152*
Y0097098*
Y0097044*
Y009699*
Y0096936*
Y0096882*
Y0096828*
Y0096773*
Y0096719*
Y0096665*
Y0096611*
Y0096557*
Y0096503*
Y0096449*
Y0096395*
Y0096341*
Y0096287*
Y0096233*
Y0096179*
Y0096125*
Y0096071*
Y0096017*
Y0095963*
Y0095908*
Y0095854*
Y00958*
Y0095746*
Y0095692*
Y0095638*
Y0095584*
Y009553*
Y0095476*
Y0095422*
Y0095368*
Y0095314*
Y009526*
Y0095206*
Y0095152*
Y0095098*
Y0095043*
Y009499*
Y0094935*
Y0094881*
X0630482*
Y0094827*
Y0094773*
Y0094719*
Y0094665*
Y0094611*
X0630536*
Y0094557*
Y0094503*
X063059*
Y0094449*
Y0094395*
X0630644*
Y0094341*
X0630698*
Y0094287*
X0630752*
Y0094233*
X0630806*
Y0094178*
X063086*
Y0094125*
X0630914*
Y009407*
X0630968*
Y0094016*
X0631022*
Y0093962*
X0631076*
Y0093908*
X063113*
Y0093854*
X0631184*
Y00938*
X0631239*
Y0093746*
X0631293*
Y0093692*
X0631347*
Y0093638*
X0631401*
Y0093584*
X0631455*
Y009353*
X0631509*
Y0093476*
X0631563*
Y0093422*
X0631617*
Y0093368*
X0631671*
Y0093313*
X0631725*
Y009326*
X0631779*
Y0093205*
X0631833*
Y0093151*
X0631887*
Y0093097*
X0631941*
Y0093043*
X0631995*
Y0092989*
X0632049*
Y0092935*
X0632103*
Y0092881*
X0632212*
Y0092827*
X0632428*
Y0092773*
X0639294*
Y0092827*
X0639348*
Y0092881*
X0639402*
Y0092935*
Y0092989*
X0639456*
Y0093043*
Y0093097*
Y0093151*
Y0093205*
Y009326*
Y0093313*
Y0093368*
Y0093422*
Y0093476*
Y009353*
Y0093584*
Y0093638*
Y0093692*
Y0093746*
Y00938*
Y0093854*
Y0093908*
Y0093962*
Y0094016*
Y009407*
Y0094125*
Y0094178*
Y0094233*
Y0094287*
Y0094341*
Y0094395*
Y0094449*
Y0094503*
Y0094557*
Y0094611*
Y0094665*
Y0094719*
Y0094773*
Y0094827*
Y0094881*
Y0094935*
Y009499*
Y0095043*
Y0095098*
Y0095152*
Y0095206*
Y009526*
Y0095314*
X0639402*
Y0095368*
Y0095422*
X0639348*
Y0095476*
X063924*
Y009553*
X0633455*
Y0095584*
X0633401*
Y0095638*
Y0095692*
Y0095746*
Y00958*
Y0095854*
Y0095908*
Y0095963*
Y0096017*
Y0096071*
Y0096125*
Y0096179*
Y0096233*
Y0096287*
Y0096341*
Y0096395*
Y0096449*
Y0096503*
Y0096557*
Y0096611*
Y0096665*
Y0096719*
Y0096773*
Y0096828*
Y0096882*
Y0096936*
Y009699*
Y0097044*
Y0097098*
Y0097152*
Y0097206*
Y009726*
Y0097314*
Y0097368*
Y0097422*
X0633455*
Y0097476*
X0638429*
Y009753*
X0638537*
Y0097584*
Y0097638*
X0638591*
Y0097693*
Y0097747*
Y0097801*
Y0097855*
Y0097909*
Y0097963*
Y0098017*
Y0098071*
Y0098125*
Y0098179*
Y0098233*
Y0098287*
Y0098341*
Y0098395*
Y0098449*
Y0098504*
Y0098558*
Y0098612*
Y0098666*
Y009872*
Y0098774*
Y0098828*
Y0098882*
Y0098936*
Y009899*
Y0099044*
Y0099098*
Y0099152*
Y0099206*
Y009926*
Y0099314*
Y0099369*
Y0099423*
Y0099477*
Y0099531*
Y0099585*
Y0099639*
X0638537*
Y0099693*
Y0099747*
X0638429*
Y0099801*
X0633455*
Y0099855*
X0633401*
Y0099909*
Y0099963*
Y0100017*
Y0100071*
Y0100125*
Y0100179*
Y0100233*
Y0100287*
Y0100342*
Y0100396*
Y010045*
Y0100504*
Y0100558*
Y0100612*
Y0100666*
Y010072*
Y0100774*
Y0100828*
Y0100882*
Y0100936*
Y010099*
Y0101044*
Y0101099*
Y0101153*
Y0101207*
Y0101261*
Y0101315*
Y0101369*
Y0101423*
Y0101477*
Y0101531*
Y0101585*
Y0101639*
Y0101693*
Y0101747*
X0633455*
Y0101801*
X0639294*
Y0101855*
X0639348*
Y0101909*
X0639402*
Y0101963*
X0639456*
Y0102017*
Y0102072*
Y0102126*
Y010218*
Y0102234*
Y0102288*
Y0102342*
Y0102396*
Y010245*
Y0102504*
Y0102558*
Y0102612*
Y0102666*
Y010272*
Y0102774*
Y0102828*
Y0102883*
Y0102937*
Y0102991*
Y0103045*
Y0103099*
Y0103153*
Y0103207*
Y0103261*
Y0103315*
Y0103369*
Y0103423*
Y0103477*
Y0103531*
Y0103585*
Y0103639*
Y0103693*
Y0103747*
Y0103802*
Y0103856*
Y010391*
Y0103964*
Y0104018*
Y0104072*
Y0104126*
Y010418*
Y0104234*
Y0104288*
X0639402*
Y0104342*
Y0104396*
X0639348*
Y010445*
X0639294*
Y0104504*
X0639186*
Y0104558*
G37*
G36*
X0611506D02*
X0611398D01*
Y0104504*
X0611344*
Y0104558*
X0603018*
Y0104504*
X0602856*
Y010445*
X0602802*
Y0104396*
Y0104342*
X0602748*
Y0104288*
Y0104234*
Y010418*
Y0104126*
Y0104072*
Y0104018*
Y0103964*
Y010391*
Y0103856*
Y0103802*
Y0103747*
Y0103693*
Y0103639*
Y0103585*
Y0103531*
Y0103477*
Y0103423*
Y0103369*
Y0103315*
Y0103261*
Y0103207*
Y0103153*
Y0103099*
Y0103045*
Y0102991*
Y0102937*
Y0102883*
Y0102828*
Y0102774*
Y010272*
Y0102666*
Y0102612*
Y0102558*
Y0102504*
Y010245*
Y0102396*
Y0102342*
Y0102288*
Y0102234*
Y010218*
Y0102126*
Y0102072*
Y0102017*
Y0101963*
Y0101909*
Y0101855*
X0602802*
Y0101801*
X0602856*
Y0101747*
X060291*
Y0101693*
X0603018*
Y0101639*
X0605613*
Y0101585*
X0605667*
Y0101531*
X0605721*
Y0101477*
Y0101423*
X0605775*
Y0101369*
Y0101315*
Y0101261*
Y0101207*
Y0101153*
Y0101099*
Y0101044*
Y010099*
Y0100936*
Y0100882*
Y0100828*
Y0100774*
Y010072*
Y0100666*
Y0100612*
Y0100558*
Y0100504*
Y010045*
Y0100396*
Y0100342*
Y0100287*
Y0100233*
Y0100179*
Y0100125*
Y0100071*
Y0100017*
Y0099963*
Y0099909*
Y0099855*
Y0099801*
Y0099747*
Y0099693*
Y0099639*
Y0099585*
Y0099531*
Y0099477*
Y0099423*
Y0099369*
Y0099314*
Y009926*
Y0099206*
Y0099152*
Y0099098*
Y0099044*
Y009899*
Y0098936*
Y0098882*
Y0098828*
Y0098774*
Y009872*
Y0098666*
Y0098612*
Y0098558*
Y0098504*
Y0098449*
Y0098395*
Y0098341*
Y0098287*
Y0098233*
Y0098179*
Y0098125*
Y0098071*
Y0098017*
Y0097963*
Y0097909*
Y0097855*
Y0097801*
Y0097747*
Y0097693*
Y0097638*
Y0097584*
Y009753*
Y0097476*
Y0097422*
Y0097368*
Y0097314*
Y009726*
Y0097206*
Y0097152*
Y0097098*
Y0097044*
Y009699*
Y0096936*
Y0096882*
Y0096828*
Y0096773*
Y0096719*
Y0096665*
Y0096611*
Y0096557*
Y0096503*
Y0096449*
Y0096395*
Y0096341*
Y0096287*
Y0096233*
Y0096179*
Y0096125*
Y0096071*
Y0096017*
Y0095963*
Y0095908*
Y0095854*
Y00958*
Y0095746*
Y0095692*
Y0095638*
Y0095584*
Y009553*
Y0095476*
Y0095422*
Y0095368*
Y0095314*
Y009526*
Y0095206*
Y0095152*
Y0095098*
Y0095043*
Y009499*
Y0094935*
Y0094881*
Y0094827*
Y0094773*
Y0094719*
Y0094665*
Y0094611*
Y0094557*
Y0094503*
Y0094449*
Y0094395*
Y0094341*
Y0094287*
Y0094233*
Y0094178*
Y0094125*
Y009407*
Y0094016*
Y0093962*
Y0093908*
Y0093854*
Y00938*
Y0093746*
Y0093692*
Y0093638*
Y0093584*
Y009353*
Y0093476*
Y0093422*
Y0093368*
Y0093313*
Y009326*
Y0093205*
Y0093151*
Y0093097*
Y0093043*
Y0092989*
Y0092935*
X0605829*
Y0092881*
X0605883*
Y0092827*
X0605937*
Y0092773*
X0608587*
Y0092827*
X0608641*
Y0092881*
X0608695*
Y0092935*
Y0092989*
Y0093043*
X0608749*
Y0093097*
Y0093151*
Y0093205*
Y009326*
Y0093313*
Y0093368*
Y0093422*
Y0093476*
Y009353*
Y0093584*
Y0093638*
Y0093692*
Y0093746*
Y00938*
Y0093854*
Y0093908*
Y0093962*
Y0094016*
Y009407*
Y0094125*
Y0094178*
Y0094233*
Y0094287*
Y0094341*
Y0094395*
Y0094449*
Y0094503*
Y0094557*
Y0094611*
Y0094665*
Y0094719*
Y0094773*
Y0094827*
Y0094881*
Y0094935*
Y009499*
Y0095043*
Y0095098*
Y0095152*
Y0095206*
Y009526*
Y0095314*
Y0095368*
Y0095422*
Y0095476*
Y009553*
Y0095584*
Y0095638*
Y0095692*
Y0095746*
Y00958*
Y0095854*
Y0095908*
Y0095963*
Y0096017*
Y0096071*
Y0096125*
Y0096179*
Y0096233*
Y0096287*
Y0096341*
Y0096395*
Y0096449*
Y0096503*
Y0096557*
Y0096611*
Y0096665*
Y0096719*
Y0096773*
Y0096828*
Y0096882*
Y0096936*
Y009699*
Y0097044*
Y0097098*
Y0097152*
Y0097206*
Y009726*
Y0097314*
Y0097368*
Y0097422*
Y0097476*
Y009753*
Y0097584*
Y0097638*
Y0097693*
Y0097747*
Y0097801*
Y0097855*
Y0097909*
Y0097963*
Y0098017*
Y0098071*
Y0098125*
Y0098179*
Y0098233*
Y0098287*
Y0098341*
Y0098395*
Y0098449*
Y0098504*
Y0098558*
Y0098612*
Y0098666*
Y009872*
Y0098774*
Y0098828*
Y0098882*
Y0098936*
Y009899*
Y0099044*
Y0099098*
Y0099152*
Y0099206*
Y009926*
Y0099314*
Y0099369*
Y0099423*
Y0099477*
Y0099531*
Y0099585*
Y0099639*
Y0099693*
Y0099747*
Y0099801*
Y0099855*
Y0099909*
Y0099963*
Y0100017*
Y0100071*
Y0100125*
Y0100179*
Y0100233*
Y0100287*
Y0100342*
Y0100396*
Y010045*
Y0100504*
Y0100558*
Y0100612*
Y0100666*
Y010072*
Y0100774*
Y0100828*
Y0100882*
Y0100936*
Y010099*
Y0101044*
Y0101099*
Y0101153*
Y0101207*
Y0101261*
Y0101315*
Y0101369*
Y0101423*
Y0101477*
Y0101531*
X0608803*
Y0101585*
X0608857*
Y0101639*
X0611452*
Y0101693*
X0611614*
Y0101747*
X0611668*
Y0101801*
X0611722*
Y0101855*
Y0101909*
Y0101963*
X0611776*
Y0102017*
Y0102072*
Y0102126*
Y010218*
Y0102234*
Y0102288*
Y0102342*
Y0102396*
Y010245*
Y0102504*
Y0102558*
Y0102612*
Y0102666*
Y010272*
Y0102774*
Y0102828*
Y0102883*
Y0102937*
Y0102991*
Y0103045*
Y0103099*
Y0103153*
Y0103207*
Y0103261*
Y0103315*
Y0103369*
Y0103423*
Y0103477*
Y0103531*
Y0103585*
Y0103639*
Y0103693*
Y0103747*
Y0103802*
Y0103856*
Y010391*
Y0103964*
Y0104018*
Y0104072*
Y0104126*
Y010418*
Y0104234*
X0611722*
Y0104288*
Y0104342*
Y0104396*
X0611668*
Y010445*
X0611614*
Y0104504*
X0611506*
Y0104558*
G37*
G36*
X0625292D02*
X061702D01*
Y0104504*
X0616858*
Y010445*
X0616804*
Y0104396*
Y0104342*
X061675*
Y0104288*
Y0104234*
Y010418*
Y0104126*
Y0104072*
Y0104018*
Y0103964*
Y010391*
Y0103856*
Y0103802*
Y0103747*
Y0103693*
Y0103639*
Y0103585*
Y0103531*
Y0103477*
Y0103423*
Y0103369*
Y0103315*
Y0103261*
Y0103207*
Y0103153*
Y0103099*
Y0103045*
Y0102991*
Y0102937*
Y0102883*
Y0102828*
Y0102774*
Y010272*
Y0102666*
Y0102612*
Y0102558*
Y0102504*
Y010245*
Y0102396*
Y0102342*
Y0102288*
Y0102234*
Y010218*
Y0102126*
Y0102072*
Y0102017*
Y0101963*
Y0101909*
Y0101855*
Y0101801*
Y0101747*
Y0101693*
Y0101639*
Y0101585*
Y0101531*
Y0101477*
Y0101423*
Y0101369*
Y0101315*
Y0101261*
Y0101207*
Y0101153*
Y0101099*
Y0101044*
Y010099*
Y0100936*
Y0100882*
Y0100828*
Y0100774*
Y010072*
Y0100666*
Y0100612*
Y0100558*
Y0100504*
Y010045*
Y0100396*
Y0100342*
Y0100287*
Y0100233*
Y0100179*
Y0100125*
Y0100071*
Y0100017*
Y0099963*
Y0099909*
Y0099855*
Y0099801*
Y0099747*
Y0099693*
Y0099639*
Y0099585*
Y0099531*
Y0099477*
Y0099423*
Y0099369*
Y0099314*
Y009926*
Y0099206*
Y0099152*
Y0099098*
Y0099044*
Y009899*
Y0098936*
Y0098882*
Y0098828*
Y0098774*
Y009872*
Y0098666*
Y0098612*
Y0098558*
Y0098504*
Y0098449*
Y0098395*
Y0098341*
Y0098287*
Y0098233*
Y0098179*
Y0098125*
Y0098071*
Y0098017*
Y0097963*
Y0097909*
Y0097855*
Y0097801*
Y0097747*
Y0097693*
Y0097638*
Y0097584*
Y009753*
Y0097476*
Y0097422*
Y0097368*
Y0097314*
Y009726*
Y0097206*
Y0097152*
Y0097098*
Y0097044*
Y009699*
Y0096936*
Y0096882*
Y0096828*
Y0096773*
Y0096719*
Y0096665*
Y0096611*
Y0096557*
Y0096503*
Y0096449*
Y0096395*
Y0096341*
Y0096287*
Y0096233*
Y0096179*
Y0096125*
Y0096071*
Y0096017*
Y0095963*
Y0095908*
Y0095854*
Y00958*
Y0095746*
Y0095692*
Y0095638*
Y0095584*
Y009553*
Y0095476*
Y0095422*
Y0095368*
Y0095314*
Y009526*
Y0095206*
Y0095152*
Y0095098*
Y0095043*
Y009499*
Y0094935*
Y0094881*
Y0094827*
Y0094773*
Y0094719*
Y0094665*
Y0094611*
Y0094557*
Y0094503*
Y0094449*
Y0094395*
Y0094341*
Y0094287*
Y0094233*
Y0094178*
Y0094125*
Y009407*
Y0094016*
Y0093962*
Y0093908*
Y0093854*
Y00938*
Y0093746*
Y0093692*
Y0093638*
Y0093584*
Y009353*
Y0093476*
Y0093422*
Y0093368*
Y0093313*
Y009326*
Y0093205*
Y0093151*
Y0093097*
Y0093043*
Y0092989*
Y0092935*
X0616804*
Y0092881*
Y0092827*
X0616912*
Y0092773*
X0619561*
Y0092827*
X0619615*
Y0092881*
X0619669*
Y0092935*
Y0092989*
X0619723*
Y0093043*
Y0093097*
Y0093151*
Y0093205*
Y009326*
Y0093313*
Y0093368*
Y0093422*
Y0093476*
Y009353*
Y0093584*
Y0093638*
Y0093692*
Y0093746*
Y00938*
Y0093854*
Y0093908*
Y0093962*
Y0094016*
Y009407*
Y0094125*
Y0094178*
Y0094233*
Y0094287*
Y0094341*
Y0094395*
Y0094449*
Y0094503*
Y0094557*
Y0094611*
Y0094665*
Y0094719*
Y0094773*
Y0094827*
Y0094881*
Y0094935*
Y009499*
Y0095043*
Y0095098*
Y0095152*
Y0095206*
Y009526*
Y0095314*
Y0095368*
Y0095422*
Y0095476*
Y009553*
Y0095584*
Y0095638*
Y0095692*
Y0095746*
Y00958*
Y0095854*
Y0095908*
Y0095963*
Y0096017*
Y0096071*
Y0096125*
Y0096179*
Y0096233*
Y0096287*
Y0096341*
Y0096395*
Y0096449*
Y0096503*
Y0096557*
Y0096611*
Y0096665*
Y0096719*
Y0096773*
Y0096828*
Y0096882*
Y0096936*
Y009699*
Y0097044*
Y0097098*
Y0097152*
Y0097206*
Y009726*
Y0097314*
Y0097368*
Y0097422*
Y0097476*
Y009753*
Y0097584*
Y0097638*
Y0097693*
Y0097747*
Y0097801*
Y0097855*
Y0097909*
Y0097963*
Y0098017*
Y0098071*
Y0098125*
Y0098179*
Y0098233*
Y0098287*
Y0098341*
Y0098395*
Y0098449*
Y0098504*
Y0098558*
Y0098612*
Y0098666*
Y009872*
Y0098774*
Y0098828*
Y0098882*
Y0098936*
Y009899*
Y0099044*
Y0099098*
Y0099152*
Y0099206*
Y009926*
Y0099314*
Y0099369*
Y0099423*
Y0099477*
Y0099531*
Y0099585*
Y0099639*
Y0099693*
Y0099747*
Y0099801*
Y0099855*
Y0099909*
Y0099963*
Y0100017*
Y0100071*
Y0100125*
Y0100179*
Y0100233*
Y0100287*
Y0100342*
Y0100396*
Y010045*
Y0100504*
Y0100558*
Y0100612*
Y0100666*
Y010072*
Y0100774*
Y0100828*
Y0100882*
Y0100936*
Y010099*
Y0101044*
Y0101099*
Y0101153*
Y0101207*
Y0101261*
Y0101315*
Y0101369*
Y0101423*
Y0101477*
Y0101531*
Y0101585*
Y0101639*
X0621561*
Y0101585*
Y0101531*
Y0101477*
Y0101423*
Y0101369*
Y0101315*
Y0101261*
Y0101207*
Y0101153*
Y0101099*
Y0101044*
Y010099*
Y0100936*
Y0100882*
Y0100828*
Y0100774*
Y010072*
Y0100666*
Y0100612*
Y0100558*
Y0100504*
Y010045*
Y0100396*
Y0100342*
Y0100287*
Y0100233*
Y0100179*
Y0100125*
Y0100071*
Y0100017*
Y0099963*
Y0099909*
Y0099855*
Y0099801*
Y0099747*
Y0099693*
Y0099639*
Y0099585*
Y0099531*
Y0099477*
Y0099423*
Y0099369*
Y0099314*
Y009926*
Y0099206*
Y0099152*
Y0099098*
Y0099044*
Y009899*
Y0098936*
Y0098882*
Y0098828*
Y0098774*
Y009872*
Y0098666*
Y0098612*
Y0098558*
Y0098504*
Y0098449*
Y0098395*
Y0098341*
Y0098287*
Y0098233*
Y0098179*
Y0098125*
Y0098071*
Y0098017*
Y0097963*
Y0097909*
Y0097855*
Y0097801*
Y0097747*
Y0097693*
Y0097638*
Y0097584*
Y009753*
Y0097476*
Y0097422*
Y0097368*
Y0097314*
Y009726*
Y0097206*
Y0097152*
Y0097098*
Y0097044*
Y009699*
Y0096936*
Y0096882*
Y0096828*
Y0096773*
Y0096719*
Y0096665*
Y0096611*
Y0096557*
Y0096503*
Y0096449*
Y0096395*
Y0096341*
Y0096287*
Y0096233*
Y0096179*
Y0096125*
Y0096071*
Y0096017*
Y0095963*
Y0095908*
Y0095854*
Y00958*
Y0095746*
Y0095692*
Y0095638*
Y0095584*
Y009553*
Y0095476*
Y0095422*
Y0095368*
Y0095314*
Y009526*
Y0095206*
Y0095152*
Y0095098*
Y0095043*
Y009499*
Y0094935*
Y0094881*
Y0094827*
Y0094773*
Y0094719*
Y0094665*
Y0094611*
Y0094557*
Y0094503*
Y0094449*
Y0094395*
Y0094341*
Y0094287*
Y0094233*
Y0094178*
Y0094125*
Y009407*
Y0094016*
Y0093962*
Y0093908*
Y0093854*
Y00938*
Y0093746*
Y0093692*
Y0093638*
Y0093584*
Y009353*
Y0093476*
Y0093422*
Y0093368*
Y0093313*
Y009326*
Y0093205*
Y0093151*
Y0093097*
Y0093043*
Y0092989*
X0621615*
Y0092935*
Y0092881*
X0621669*
Y0092827*
X0621778*
Y0092773*
X0624156*
Y0092827*
X062421*
Y0092881*
X0624264*
Y0092935*
X0624319*
Y0092989*
Y0093043*
Y0093097*
Y0093151*
Y0093205*
Y009326*
Y0093313*
Y0093368*
Y0093422*
Y0093476*
Y009353*
Y0093584*
Y0093638*
Y0093692*
Y0093746*
Y00938*
Y0093854*
Y0093908*
Y0093962*
Y0094016*
Y009407*
Y0094125*
Y0094178*
Y0094233*
Y0094287*
Y0094341*
Y0094395*
Y0094449*
Y0094503*
Y0094557*
Y0094611*
Y0094665*
Y0094719*
Y0094773*
Y0094827*
Y0094881*
Y0094935*
Y009499*
Y0095043*
Y0095098*
Y0095152*
Y0095206*
Y009526*
Y0095314*
Y0095368*
Y0095422*
Y0095476*
Y009553*
Y0095584*
Y0095638*
Y0095692*
Y0095746*
Y00958*
Y0095854*
Y0095908*
Y0095963*
Y0096017*
Y0096071*
Y0096125*
Y0096179*
Y0096233*
Y0096287*
Y0096341*
Y0096395*
Y0096449*
Y0096503*
Y0096557*
Y0096611*
Y0096665*
Y0096719*
Y0096773*
Y0096828*
Y0096882*
Y0096936*
Y009699*
Y0097044*
Y0097098*
Y0097152*
Y0097206*
Y009726*
Y0097314*
Y0097368*
Y0097422*
Y0097476*
Y009753*
Y0097584*
Y0097638*
Y0097693*
Y0097747*
Y0097801*
Y0097855*
Y0097909*
Y0097963*
Y0098017*
Y0098071*
Y0098125*
Y0098179*
Y0098233*
Y0098287*
Y0098341*
Y0098395*
Y0098449*
Y0098504*
Y0098558*
Y0098612*
Y0098666*
Y009872*
Y0098774*
Y0098828*
Y0098882*
Y0098936*
Y009899*
Y0099044*
Y0099098*
Y0099152*
Y0099206*
Y009926*
Y0099314*
Y0099369*
Y0099423*
Y0099477*
Y0099531*
Y0099585*
Y0099639*
Y0099693*
Y0099747*
Y0099801*
Y0099855*
Y0099909*
Y0099963*
Y0100017*
Y0100071*
Y0100125*
Y0100179*
Y0100233*
Y0100287*
Y0100342*
Y0100396*
Y010045*
Y0100504*
Y0100558*
Y0100612*
Y0100666*
Y010072*
Y0100774*
Y0100828*
Y0100882*
Y0100936*
Y010099*
Y0101044*
Y0101099*
Y0101153*
Y0101207*
Y0101261*
Y0101315*
Y0101369*
Y0101423*
Y0101477*
Y0101531*
Y0101585*
Y0101639*
X0625075*
Y0101693*
X062513*
Y0101639*
X0625292*
Y0101693*
Y0101747*
Y0101801*
Y0101855*
Y0101909*
Y0101963*
Y0102017*
Y0102072*
Y0102126*
Y010218*
Y0102234*
Y0102288*
Y0102342*
Y0102396*
Y010245*
Y0102504*
Y0102558*
Y0102612*
Y0102666*
Y010272*
Y0102774*
Y0102828*
Y0102883*
Y0102937*
Y0102991*
Y0103045*
Y0103099*
Y0103153*
Y0103207*
Y0103261*
Y0103315*
Y0103369*
Y0103423*
Y0103477*
Y0103531*
Y0103585*
Y0103639*
Y0103693*
Y0103747*
Y0103802*
Y0103856*
Y010391*
Y0103964*
Y0104018*
Y0104072*
Y0104126*
Y010418*
Y0104234*
Y0104288*
Y0104342*
Y0104396*
Y010445*
Y0104504*
Y0104558*
G37*
G36*
X0615182D02*
X0612695D01*
Y0104504*
X0612533*
Y010445*
Y0104396*
X0612479*
Y0104342*
Y0104288*
X0612425*
Y0104234*
Y010418*
Y0104126*
Y0104072*
Y0104018*
Y0103964*
Y010391*
Y0103856*
Y0103802*
Y0103747*
Y0103693*
Y0103639*
Y0103585*
Y0103531*
Y0103477*
Y0103423*
Y0103369*
Y0103315*
Y0103261*
Y0103207*
Y0103153*
Y0103099*
Y0103045*
Y0102991*
Y0102937*
Y0102883*
Y0102828*
Y0102774*
Y010272*
Y0102666*
Y0102612*
Y0102558*
Y0102504*
Y010245*
Y0102396*
Y0102342*
Y0102288*
Y0102234*
Y010218*
Y0102126*
Y0102072*
Y0102017*
Y0101963*
Y0101909*
Y0101855*
Y0101801*
Y0101747*
Y0101693*
Y0101639*
Y0101585*
Y0101531*
Y0101477*
Y0101423*
Y0101369*
Y0101315*
Y0101261*
Y0101207*
Y0101153*
Y0101099*
Y0101044*
Y010099*
Y0100936*
Y0100882*
Y0100828*
Y0100774*
Y010072*
Y0100666*
Y0100612*
Y0100558*
Y0100504*
Y010045*
Y0100396*
Y0100342*
Y0100287*
Y0100233*
Y0100179*
Y0100125*
Y0100071*
Y0100017*
Y0099963*
Y0099909*
Y0099855*
Y0099801*
Y0099747*
Y0099693*
Y0099639*
Y0099585*
Y0099531*
Y0099477*
Y0099423*
Y0099369*
Y0099314*
Y009926*
Y0099206*
Y0099152*
Y0099098*
Y0099044*
Y009899*
Y0098936*
Y0098882*
Y0098828*
Y0098774*
Y009872*
Y0098666*
Y0098612*
Y0098558*
Y0098504*
Y0098449*
Y0098395*
Y0098341*
Y0098287*
Y0098233*
Y0098179*
Y0098125*
Y0098071*
Y0098017*
Y0097963*
Y0097909*
Y0097855*
Y0097801*
Y0097747*
Y0097693*
Y0097638*
Y0097584*
Y009753*
Y0097476*
Y0097422*
Y0097368*
Y0097314*
Y009726*
Y0097206*
Y0097152*
Y0097098*
Y0097044*
Y009699*
Y0096936*
Y0096882*
Y0096828*
Y0096773*
Y0096719*
Y0096665*
Y0096611*
Y0096557*
Y0096503*
Y0096449*
Y0096395*
Y0096341*
Y0096287*
Y0096233*
Y0096179*
Y0096125*
Y0096071*
Y0096017*
Y0095963*
Y0095908*
Y0095854*
Y00958*
Y0095746*
Y0095692*
Y0095638*
Y0095584*
Y009553*
Y0095476*
Y0095422*
Y0095368*
Y0095314*
Y009526*
Y0095206*
Y0095152*
Y0095098*
Y0095043*
Y009499*
Y0094935*
Y0094881*
Y0094827*
Y0094773*
Y0094719*
Y0094665*
Y0094611*
Y0094557*
Y0094503*
Y0094449*
Y0094395*
Y0094341*
Y0094287*
Y0094233*
Y0094178*
Y0094125*
Y009407*
Y0094016*
Y0093962*
Y0093908*
Y0093854*
Y00938*
Y0093746*
Y0093692*
Y0093638*
Y0093584*
Y009353*
Y0093476*
Y0093422*
Y0093368*
Y0093313*
Y009326*
Y0093205*
Y0093151*
Y0093097*
Y0093043*
Y0092989*
X0612479*
Y0092935*
Y0092881*
X0612533*
Y0092827*
X0612587*
Y0092773*
X061529*
Y0092827*
X0615344*
Y0092881*
X0615398*
Y0092935*
Y0092989*
Y0093043*
Y0093097*
Y0093151*
Y0093205*
Y009326*
Y0093313*
Y0093368*
Y0093422*
Y0093476*
Y009353*
Y0093584*
Y0093638*
Y0093692*
Y0093746*
Y00938*
Y0093854*
Y0093908*
Y0093962*
Y0094016*
Y009407*
Y0094125*
Y0094178*
Y0094233*
Y0094287*
Y0094341*
Y0094395*
Y0094449*
Y0094503*
Y0094557*
Y0094611*
Y0094665*
Y0094719*
Y0094773*
Y0094827*
Y0094881*
Y0094935*
Y009499*
Y0095043*
Y0095098*
Y0095152*
Y0095206*
Y009526*
Y0095314*
Y0095368*
Y0095422*
Y0095476*
Y009553*
Y0095584*
Y0095638*
Y0095692*
Y0095746*
Y00958*
Y0095854*
Y0095908*
Y0095963*
Y0096017*
Y0096071*
Y0096125*
Y0096179*
Y0096233*
Y0096287*
Y0096341*
Y0096395*
Y0096449*
Y0096503*
Y0096557*
Y0096611*
Y0096665*
Y0096719*
Y0096773*
Y0096828*
Y0096882*
Y0096936*
Y009699*
Y0097044*
Y0097098*
Y0097152*
Y0097206*
Y009726*
Y0097314*
Y0097368*
Y0097422*
Y0097476*
Y009753*
Y0097584*
Y0097638*
Y0097693*
Y0097747*
Y0097801*
Y0097855*
Y0097909*
Y0097963*
Y0098017*
Y0098071*
Y0098125*
Y0098179*
Y0098233*
Y0098287*
Y0098341*
Y0098395*
Y0098449*
Y0098504*
Y0098558*
Y0098612*
Y0098666*
Y009872*
Y0098774*
Y0098828*
Y0098882*
Y0098936*
Y009899*
Y0099044*
Y0099098*
Y0099152*
Y0099206*
Y009926*
Y0099314*
Y0099369*
Y0099423*
Y0099477*
Y0099531*
Y0099585*
Y0099639*
Y0099693*
Y0099747*
Y0099801*
Y0099855*
Y0099909*
Y0099963*
Y0100017*
Y0100071*
Y0100125*
Y0100179*
Y0100233*
Y0100287*
Y0100342*
Y0100396*
Y010045*
Y0100504*
Y0100558*
Y0100612*
Y0100666*
Y010072*
Y0100774*
Y0100828*
Y0100882*
Y0100936*
Y010099*
Y0101044*
Y0101099*
Y0101153*
Y0101207*
Y0101261*
Y0101315*
Y0101369*
Y0101423*
Y0101477*
Y0101531*
Y0101585*
Y0101639*
Y0101693*
Y0101747*
Y0101801*
Y0101855*
Y0101909*
Y0101963*
Y0102017*
Y0102072*
Y0102126*
Y010218*
Y0102234*
Y0102288*
Y0102342*
Y0102396*
Y010245*
Y0102504*
Y0102558*
Y0102612*
Y0102666*
Y010272*
Y0102774*
Y0102828*
Y0102883*
Y0102937*
Y0102991*
Y0103045*
Y0103099*
Y0103153*
Y0103207*
Y0103261*
Y0103315*
Y0103369*
Y0103423*
Y0103477*
Y0103531*
Y0103585*
Y0103639*
Y0103693*
Y0103747*
Y0103802*
Y0103856*
Y010391*
Y0103964*
Y0104018*
Y0104072*
Y0104126*
Y010418*
Y0104234*
Y0104288*
Y0104342*
Y0104396*
X0615344*
Y010445*
X061529*
Y0104504*
X0615182*
Y0104558*
G37*
G36*
X0629022Y0113262D02*
X0627022D01*
Y0113208*
X0626211*
Y0113154*
X062567*
Y01131*
X0625238*
Y0113046*
X0624913*
Y0112992*
X0624535*
Y0112938*
X062421*
Y0112884*
X062394*
Y011283*
X062367*
Y0112776*
X0623399*
Y0112722*
X0623183*
Y0112668*
X0622967*
Y0112614*
X0622751*
Y011256*
X0622535*
Y0112505*
X0622372*
Y0112452*
X0622156*
Y0112397*
X0621994*
Y0112343*
X0621832*
Y0112289*
X0621615*
Y0112235*
X0621453*
Y0112181*
X0621291*
Y0112127*
X0621129*
Y0112073*
X0621021*
Y0112019*
X0620859*
Y0111965*
X0620696*
Y0111911*
X0620534*
Y0111857*
X0620426*
Y0111803*
X0620264*
Y0111749*
X0620156*
Y0111695*
X0619994*
Y0111641*
X0619885*
Y0111586*
X0619777*
Y0111532*
X0619615*
Y0111478*
X0619507*
Y0111424*
X0619399*
Y011137*
X0619291*
Y0111316*
X0619129*
Y0111262*
X0619021*
Y0111208*
X0618912*
Y0111154*
X0618804*
Y01111*
X0618696*
Y0111046*
X0618588*
Y0110992*
X061848*
Y0110938*
X0618372*
Y0110884*
X0618264*
Y011083*
X0618155*
Y0110776*
X0618101*
Y0110722*
X0617993*
Y0110668*
X0617885*
Y0110613*
X0617777*
Y0110559*
X0617669*
Y0110505*
X0617615*
Y0110451*
X0617507*
Y0110397*
X0617399*
Y0110343*
X0617345*
Y0110289*
X0617236*
Y0110235*
X0617128*
Y0110181*
X0617074*
Y0110127*
X0616966*
Y0110073*
X0616858*
Y0110019*
X0616804*
Y0109965*
X0616696*
Y0109911*
X0616642*
Y0109856*
X0616534*
Y0109802*
X061648*
Y0109748*
X0616371*
Y0109694*
X0616317*
Y010964*
X0616209*
Y0109586*
X0616155*
Y0109532*
X0616047*
Y0109478*
X0615993*
Y0109424*
X0615939*
Y010937*
X0615831*
Y0109316*
X0615777*
Y0109262*
X0615669*
Y0109208*
X0615615*
Y0109154*
X061556*
Y01091*
X0615452*
Y0109046*
X0615398*
Y0108992*
X0615344*
Y0108938*
X0615236*
Y0108883*
X0615182*
Y0108829*
X0615128*
Y0108775*
X0615074*
Y0108721*
X0614966*
Y0108667*
X0614912*
Y0108613*
X0614858*
Y0108559*
X0614804*
Y0108505*
X0614696*
Y0108451*
X0614641*
Y0108397*
X0614587*
Y0108343*
X0614533*
Y0108289*
X0614479*
Y0108235*
X0614371*
Y0108181*
X0614317*
Y0108126*
X0614263*
Y0108072*
X0614209*
Y0108018*
X0614155*
Y0107964*
X0614101*
Y010791*
X0614047*
Y0107856*
X0613993*
Y0107802*
X0613885*
Y0107748*
X0613831*
Y0107694*
X0613776*
Y010764*
X0613722*
Y0107586*
X0613668*
Y0107532*
X0613614*
Y0107478*
X061356*
Y0107424*
X0613506*
Y010737*
X0613452*
Y0107316*
X0613398*
Y0107262*
X0613344*
Y0107208*
X061329*
Y0107153*
X0613236*
Y0107099*
X0613182*
Y0107045*
X0613128*
Y0106991*
X0613074*
Y0106937*
X061302*
Y0106883*
X0612965*
Y0106829*
X0612912*
Y0106775*
X0612857*
Y0106721*
X0612803*
Y0106667*
X0612749*
Y0106613*
X0612695*
Y0106559*
X0612641*
Y0106505*
X0612587*
Y0106451*
Y0106397*
X0612533*
Y0106342*
X0612479*
Y0106288*
X0612425*
Y0106234*
X0612371*
Y010618*
X0612317*
Y0106126*
X0612263*
Y0106072*
X0612209*
Y0106018*
X0612155*
Y0105964*
Y010591*
X0612101*
Y0105856*
X0612046*
Y0105802*
X0611992*
Y0105748*
X0611938*
Y0105694*
X0611884*
Y010564*
Y0105586*
X061183*
Y0105532*
X0611776*
Y0105477*
X0611722*
Y0105423*
X0612587*
Y0105477*
X0612641*
Y0105532*
X0612695*
Y0105586*
Y010564*
X0612749*
Y0105694*
X0612803*
Y0105748*
X0612857*
Y0105802*
X0612912*
Y0105856*
X0612965*
Y010591*
X061302*
Y0105964*
X0613074*
Y0106018*
X0613128*
Y0106072*
Y0106126*
X0613182*
Y010618*
X0613236*
Y0106234*
X061329*
Y0106288*
X0613344*
Y0106342*
X0613398*
Y0106397*
X0613452*
Y0106451*
X0613506*
Y0106505*
X061356*
Y0106559*
X0613614*
Y0106613*
X0613668*
Y0106667*
X0613722*
Y0106721*
X0613776*
Y0106775*
X0613831*
Y0106829*
X0613885*
Y0106883*
X0613939*
Y0106937*
X0613993*
Y0106991*
X0614047*
Y0107045*
X0614101*
Y0107099*
X0614155*
Y0107153*
X0614209*
Y0107208*
X0614317*
Y0107262*
X0614371*
Y0107316*
X0614425*
Y010737*
X0614479*
Y0107424*
X0614533*
Y0107478*
X0614587*
Y0107532*
X0614641*
Y0107586*
X0614696*
Y010764*
X061475*
Y0107694*
X0614858*
Y0107748*
X0614912*
Y0107802*
X0614966*
Y0107856*
X061502*
Y010791*
X0615074*
Y0107964*
X0615182*
Y0108018*
X0615236*
Y0108072*
X061529*
Y0108126*
X0615344*
Y0108181*
X0615452*
Y0108235*
X0615507*
Y0108289*
X061556*
Y0108343*
X0615615*
Y0108397*
X0615723*
Y0108451*
X0615777*
Y0108505*
X0615831*
Y0108559*
X0615939*
Y0108613*
X0615993*
Y0108667*
X0616047*
Y0108721*
X0616155*
Y0108775*
X0616209*
Y0108829*
X0616263*
Y0108883*
X0616371*
Y0108938*
X0616426*
Y0108992*
X0616534*
Y0109046*
X0616588*
Y01091*
X0616696*
Y0109154*
X061675*
Y0109208*
X0616858*
Y0109262*
X0616912*
Y0109316*
X061702*
Y010937*
X0617074*
Y0109424*
X0617182*
Y0109478*
X0617236*
Y0109532*
X0617345*
Y0109586*
X0617453*
Y010964*
X0617507*
Y0109694*
X0617615*
Y0109748*
X0617723*
Y0109802*
X0617777*
Y0109856*
X0617885*
Y0109911*
X0617993*
Y0109965*
X0618047*
Y0110019*
X0618155*
Y0110073*
X0618264*
Y0110127*
X0618372*
Y0110181*
X061848*
Y0110235*
X0618588*
Y0110289*
X0618696*
Y0110343*
X061875*
Y0110397*
X0618858*
Y0110451*
X0618966*
Y0110505*
X0619074*
Y0110559*
X0619183*
Y0110613*
X0619345*
Y0110668*
X0619453*
Y0110722*
X0619561*
Y0110776*
X0619669*
Y011083*
X0619777*
Y0110884*
X0619885*
Y0110938*
X0620048*
Y0110992*
X0620156*
Y0111046*
X0620264*
Y01111*
X0620426*
Y0111154*
X0620534*
Y0111208*
X0620696*
Y0111262*
X0620859*
Y0111316*
X0620967*
Y011137*
X0621129*
Y0111424*
X0621291*
Y0111478*
X0621453*
Y0111532*
X0621561*
Y0111586*
X0621778*
Y0111641*
X062194*
Y0111695*
X0622102*
Y0111749*
X0622264*
Y0111803*
X062248*
Y0111857*
X0622643*
Y0111911*
X0622859*
Y0111965*
X0623075*
Y0112019*
X0623291*
Y0112073*
X0623508*
Y0112127*
X0623778*
Y0112181*
X0624048*
Y0112235*
X0624264*
Y0112289*
X0624643*
Y0112343*
X0624967*
Y0112397*
X0625346*
Y0112452*
X0625778*
Y0112505*
X0626373*
Y011256*
X0627346*
Y0112614*
X0628698*
Y011256*
X0628752*
Y0112614*
X0628806*
Y011256*
X0629671*
Y0112505*
X0630265*
Y0112452*
X0630752*
Y0112397*
X0631076*
Y0112343*
X0631401*
Y0112289*
X0631725*
Y0112235*
X0631995*
Y0112181*
X0632266*
Y0112127*
X0632536*
Y0112073*
X0632752*
Y0112019*
X0632969*
Y0111965*
X0633185*
Y0111911*
X0633401*
Y0111857*
X0633563*
Y0111803*
X0633779*
Y0111749*
X0633942*
Y0111695*
X0634104*
Y0111641*
X0634266*
Y0111586*
X0634428*
Y0111532*
X063459*
Y0111478*
X0634753*
Y0111424*
X0634915*
Y011137*
X0635077*
Y0111316*
X0635185*
Y0111262*
X0635347*
Y0111208*
X0635455*
Y0111154*
X0635617*
Y01111*
X0635726*
Y0111046*
X0635888*
Y0110992*
X0635996*
Y0110938*
X0636104*
Y0110884*
X0636266*
Y011083*
X0636374*
Y0110776*
X0636482*
Y0110722*
X0636591*
Y0110668*
X0636699*
Y0110613*
X0636861*
Y0110559*
X0636969*
Y0110505*
X0637023*
Y0110451*
X0637131*
Y0110397*
X0637239*
Y0110343*
X0637348*
Y0110289*
X0637456*
Y0110235*
X0637564*
Y0110181*
X0637672*
Y0110127*
X063778*
Y0110073*
X0637888*
Y0110019*
X0637942*
Y0109965*
X063805*
Y0109911*
X0638158*
Y0109856*
X0638267*
Y0109802*
X0638321*
Y0109748*
X0638429*
Y0109694*
X0638537*
Y010964*
X0638591*
Y0109586*
X0638699*
Y0109532*
X0638807*
Y0109478*
X0638861*
Y0109424*
X0638969*
Y010937*
X0639023*
Y0109316*
X0639131*
Y0109262*
X0639186*
Y0109208*
X0639294*
Y0109154*
X0639348*
Y01091*
X0639456*
Y0109046*
X063951*
Y0108992*
X0639618*
Y0108938*
X0639672*
Y0108883*
X0639726*
Y0108829*
X0639834*
Y0108775*
X0639888*
Y0108721*
X0639996*
Y0108667*
X0640051*
Y0108613*
X0640105*
Y0108559*
X0640213*
Y0108505*
X0640267*
Y0108451*
X0640321*
Y0108397*
X0640429*
Y0108343*
X0640483*
Y0108289*
X0640537*
Y0108235*
X0640591*
Y0108181*
X0640699*
Y0108126*
X0640753*
Y0108072*
X0640807*
Y0108018*
X0640862*
Y0107964*
X064097*
Y010791*
X0641024*
Y0107856*
X0641078*
Y0107802*
X0641132*
Y0107748*
X0641186*
Y0107694*
X064124*
Y010764*
X0641348*
Y0107586*
X0641402*
Y0107532*
X0641456*
Y0107478*
X064151*
Y0107424*
X0641564*
Y010737*
X0641618*
Y0107316*
X0641673*
Y0107262*
X0641726*
Y0107208*
X0641781*
Y0107153*
X0641889*
Y0107099*
X0641943*
Y0107045*
X0641997*
Y0106991*
X0642051*
Y0106937*
X0642105*
Y0106883*
X0642159*
Y0106829*
X0642213*
Y0106775*
X0642267*
Y0106721*
X0642321*
Y0106667*
X0642375*
Y0106613*
X0642429*
Y0106559*
X0642483*
Y0106505*
X0642537*
Y0106451*
X0642591*
Y0106397*
X0642646*
Y0106342*
X06427*
Y0106288*
X0642754*
Y0106234*
X0642808*
Y010618*
Y0106126*
X0642862*
Y0106072*
X0642916*
Y0106018*
X064297*
Y0105964*
X0643024*
Y010591*
X0643078*
Y0105856*
X0643132*
Y0105802*
X0643186*
Y0105748*
X064324*
Y0105694*
X0643294*
Y010564*
Y0105586*
X0643348*
Y0105532*
X0643402*
Y0105477*
X0643457*
Y0105423*
X0643511*
Y0105369*
X0643565*
Y0105315*
X0643619*
Y0105261*
Y0105207*
X0643673*
Y0105153*
X0643727*
Y0105099*
X0643781*
Y0105045*
X0643835*
Y0104991*
Y0104937*
X0643889*
Y0104883*
X0643943*
Y0104829*
X0643997*
Y0104775*
X0644051*
Y0104721*
Y0104667*
X0644105*
Y0104613*
X0644159*
Y0104558*
X0644213*
Y0104504*
Y010445*
X0644267*
Y0104396*
X0644321*
Y0104342*
X0644376*
Y0104288*
Y0104234*
X064443*
Y010418*
X0644484*
Y0104126*
Y0104072*
X0644538*
Y0104018*
X0644592*
Y0103964*
X0644646*
Y010391*
Y0103856*
X06447*
Y0103802*
X0644754*
Y0103747*
Y0103693*
X0644808*
Y0103639*
X0644862*
Y0103585*
Y0103531*
X0644916*
Y0103477*
X064497*
Y0103423*
Y0103369*
X0645024*
Y0103315*
X0645078*
Y0103261*
Y0103207*
X0645132*
Y0103153*
X0645187*
Y0103099*
Y0103045*
X064524*
Y0102991*
Y0102937*
X0645295*
Y0102883*
X0645349*
Y0102828*
Y0102774*
X0645403*
Y010272*
Y0102666*
X0645457*
Y0102612*
X0645511*
Y0102558*
Y0102504*
X0645565*
Y010245*
Y0102396*
X0645619*
Y0102342*
Y0102288*
X0645673*
Y0102234*
X0645727*
Y010218*
Y0102126*
X0645781*
Y0102072*
Y0102017*
X0645835*
Y0101963*
Y0101909*
X0645889*
Y0101855*
Y0101801*
X0645943*
Y0101747*
Y0101693*
X0645997*
Y0101639*
X0646052*
Y0101585*
Y0101531*
X0646105*
Y0101477*
Y0101423*
X064616*
Y0101369*
Y0101315*
X0646214*
Y0101261*
Y0101207*
X0646268*
Y0101153*
Y0101099*
Y0101044*
X0646322*
Y010099*
Y0100936*
X0646376*
Y0100882*
Y0100828*
X064643*
Y0100774*
Y010072*
X0646484*
Y0100666*
Y0100612*
X0646538*
Y0100558*
Y0100504*
X0646592*
Y010045*
Y0100396*
Y0100342*
X0646646*
Y0100287*
Y0100233*
X06467*
Y0100179*
Y0100125*
X0646754*
Y0100071*
Y0100017*
Y0099963*
X0646808*
Y0099909*
Y0099855*
X0646862*
Y0099801*
Y0099747*
Y0099693*
X0646916*
Y0099639*
Y0099585*
X0646971*
Y0099531*
Y0099477*
Y0099423*
X0647025*
Y0099369*
Y0099314*
Y009926*
X0647079*
Y0099206*
Y0099152*
Y0099098*
X0647133*
Y0099044*
Y009899*
X0647187*
Y0098936*
Y0098882*
Y0098828*
X0647241*
Y0098774*
Y009872*
Y0098666*
X0647295*
Y0098612*
Y0098558*
Y0098504*
Y0098449*
X0647349*
Y0098395*
Y0098341*
Y0098287*
X0647403*
Y0098233*
Y0098179*
Y0098125*
X0647457*
Y0098071*
Y0098017*
Y0097963*
Y0097909*
X0647511*
Y0097855*
Y0097801*
Y0097747*
X0647565*
Y0097693*
Y0097638*
Y0097584*
Y009753*
X0647619*
Y0097476*
Y0097422*
Y0097368*
Y0097314*
X0647673*
Y009726*
Y0097206*
Y0097152*
Y0097098*
X0647727*
Y0097044*
Y009699*
Y0096936*
Y0096882*
X0647782*
Y0096828*
Y0096773*
Y0096719*
Y0096665*
Y0096611*
X0647835*
Y0096557*
Y0096503*
Y0096449*
Y0096395*
X064789*
Y0096341*
Y0096287*
Y0096233*
Y0096179*
Y0096125*
Y0096071*
X0647944*
Y0096017*
Y0095963*
Y0095908*
Y0095854*
Y00958*
X0647998*
Y0095746*
Y0095692*
Y0095638*
Y0095584*
Y009553*
Y0095476*
X0648052*
Y0095422*
Y0095368*
Y0095314*
Y009526*
Y0095206*
Y0095152*
Y0095098*
X0648106*
Y0095043*
Y009499*
Y0094935*
Y0094881*
Y0094827*
Y0094773*
Y0094719*
Y0094665*
Y0094611*
X064816*
Y0094557*
Y0094503*
Y0094449*
Y0094395*
Y0094341*
Y0094287*
Y0094233*
Y0094178*
Y0094125*
X0648214*
Y009407*
Y0094016*
Y0093962*
Y0093908*
Y0093854*
Y00938*
Y0093746*
Y0093692*
Y0093638*
Y0093584*
Y009353*
Y0093476*
Y0093422*
Y0093368*
Y0093313*
Y009326*
Y0093205*
X0648268*
Y0093151*
Y0093097*
Y0093043*
Y0092989*
Y0092935*
Y0092881*
Y0092827*
Y0092773*
Y0092719*
Y0092665*
Y0092611*
X0648917*
Y0092665*
Y0092719*
Y0092773*
Y0092827*
Y0092881*
Y0092935*
Y0092989*
Y0093043*
Y0093097*
Y0093151*
Y0093205*
Y009326*
X0648863*
Y0093313*
X0648917*
Y0093368*
Y0093422*
Y0093476*
X0648863*
Y009353*
Y0093584*
Y0093638*
Y0093692*
Y0093746*
Y00938*
Y0093854*
Y0093908*
Y0093962*
Y0094016*
Y009407*
Y0094125*
Y0094178*
Y0094233*
X0648809*
Y0094287*
Y0094341*
Y0094395*
Y0094449*
Y0094503*
Y0094557*
Y0094611*
Y0094665*
Y0094719*
Y0094773*
X0648755*
Y0094827*
Y0094881*
Y0094935*
Y009499*
Y0095043*
Y0095098*
Y0095152*
Y0095206*
X0648701*
Y009526*
Y0095314*
Y0095368*
Y0095422*
Y0095476*
Y009553*
Y0095584*
X0648646*
Y0095638*
Y0095692*
Y0095746*
Y00958*
Y0095854*
Y0095908*
X0648592*
Y0095963*
Y0096017*
Y0096071*
Y0096125*
Y0096179*
X0648538*
Y0096233*
Y0096287*
Y0096341*
Y0096395*
Y0096449*
X0648484*
Y0096503*
Y0096557*
Y0096611*
Y0096665*
Y0096719*
X064843*
Y0096773*
Y0096828*
Y0096882*
Y0096936*
Y009699*
X0648376*
Y0097044*
Y0097098*
Y0097152*
Y0097206*
X0648322*
Y009726*
Y0097314*
Y0097368*
Y0097422*
X0648268*
Y0097476*
Y009753*
Y0097584*
Y0097638*
X0648214*
Y0097693*
Y0097747*
Y0097801*
Y0097855*
X064816*
Y0097909*
Y0097963*
Y0098017*
X0648106*
Y0098071*
Y0098125*
Y0098179*
Y0098233*
X0648052*
Y0098287*
Y0098341*
Y0098395*
X0647998*
Y0098449*
Y0098504*
Y0098558*
Y0098612*
X0647944*
Y0098666*
Y009872*
Y0098774*
X064789*
Y0098828*
Y0098882*
Y0098936*
X0647835*
Y009899*
Y0099044*
Y0099098*
X0647782*
Y0099152*
Y0099206*
Y009926*
X0647727*
Y0099314*
Y0099369*
Y0099423*
X0647673*
Y0099477*
Y0099531*
X0647619*
Y0099585*
Y0099639*
Y0099693*
X0647565*
Y0099747*
Y0099801*
Y0099855*
X0647511*
Y0099909*
Y0099963*
X0647457*
Y0100017*
Y0100071*
Y0100125*
X0647403*
Y0100179*
Y0100233*
X0647349*
Y0100287*
Y0100342*
Y0100396*
X0647295*
Y010045*
Y0100504*
X0647241*
Y0100558*
Y0100612*
X0647187*
Y0100666*
Y010072*
Y0100774*
X0647133*
Y0100828*
Y0100882*
X0647079*
Y0100936*
Y010099*
X0647025*
Y0101044*
Y0101099*
X0646971*
Y0101153*
Y0101207*
Y0101261*
X0646916*
Y0101315*
Y0101369*
X0646862*
Y0101423*
Y0101477*
X0646808*
Y0101531*
Y0101585*
X0646754*
Y0101639*
Y0101693*
X06467*
Y0101747*
Y0101801*
X0646646*
Y0101855*
Y0101909*
X0646592*
Y0101963*
Y0102017*
X0646538*
Y0102072*
Y0102126*
X0646484*
Y010218*
Y0102234*
X064643*
Y0102288*
X0646376*
Y0102342*
Y0102396*
X0646322*
Y010245*
Y0102504*
X0646268*
Y0102558*
Y0102612*
X0646214*
Y0102666*
Y010272*
X064616*
Y0102774*
X0646105*
Y0102828*
Y0102883*
X0646052*
Y0102937*
Y0102991*
X0645997*
Y0103045*
X0645943*
Y0103099*
Y0103153*
X0645889*
Y0103207*
Y0103261*
X0645835*
Y0103315*
X0645781*
Y0103369*
Y0103423*
X0645727*
Y0103477*
Y0103531*
X0645673*
Y0103585*
X0645619*
Y0103639*
Y0103693*
X0645565*
Y0103747*
X0645511*
Y0103802*
Y0103856*
X0645457*
Y010391*
X0645403*
Y0103964*
Y0104018*
X0645349*
Y0104072*
X0645295*
Y0104126*
Y010418*
X064524*
Y0104234*
X0645187*
Y0104288*
Y0104342*
X0645132*
Y0104396*
X0645078*
Y010445*
X0645024*
Y0104504*
Y0104558*
X064497*
Y0104613*
X0644916*
Y0104667*
Y0104721*
X0644862*
Y0104775*
X0644808*
Y0104829*
X0644754*
Y0104883*
Y0104937*
X06447*
Y0104991*
X0644646*
Y0105045*
X0644592*
Y0105099*
X0644538*
Y0105153*
Y0105207*
X0644484*
Y0105261*
X064443*
Y0105315*
X0644376*
Y0105369*
Y0105423*
X0644321*
Y0105477*
X0644267*
Y0105532*
X0644213*
Y0105586*
X0644159*
Y010564*
X0644105*
Y0105694*
Y0105748*
X0644051*
Y0105802*
X0643997*
Y0105856*
X0643943*
Y010591*
X0643889*
Y0105964*
X0643835*
Y0106018*
Y0106072*
X0643781*
Y0106126*
X0643727*
Y010618*
X0643673*
Y0106234*
X0643619*
Y0106288*
X0643565*
Y0106342*
X0643511*
Y0106397*
X0643457*
Y0106451*
X0643402*
Y0106505*
Y0106559*
X0643348*
Y0106613*
X0643294*
Y0106667*
X064324*
Y0106721*
X0643186*
Y0106775*
X0643132*
Y0106829*
X0643078*
Y0106883*
X0643024*
Y0106937*
X064297*
Y0106991*
X0642916*
Y0107045*
X0642862*
Y0107099*
X0642808*
Y0107153*
X0642754*
Y0107208*
X06427*
Y0107262*
X0642646*
Y0107316*
X0642591*
Y010737*
X0642537*
Y0107424*
X0642483*
Y0107478*
X0642429*
Y0107532*
X0642375*
Y0107586*
X0642321*
Y010764*
X0642267*
Y0107694*
X0642159*
Y0107748*
X0642105*
Y0107802*
X0642051*
Y0107856*
X0641997*
Y010791*
X0641943*
Y0107964*
X0641889*
Y0108018*
X0641835*
Y0108072*
X0641781*
Y0108126*
X0641726*
Y0108181*
X0641618*
Y0108235*
X0641564*
Y0108289*
X064151*
Y0108343*
X0641456*
Y0108397*
X0641402*
Y0108451*
X0641294*
Y0108505*
X064124*
Y0108559*
X0641186*
Y0108613*
X0641132*
Y0108667*
X0641078*
Y0108721*
X064097*
Y0108775*
X0640916*
Y0108829*
X0640862*
Y0108883*
X0640753*
Y0108938*
X0640699*
Y0108992*
X0640645*
Y0109046*
X0640591*
Y01091*
X0640483*
Y0109154*
X0640429*
Y0109208*
X0640321*
Y0109262*
X0640267*
Y0109316*
X0640213*
Y010937*
X0640105*
Y0109424*
X0640051*
Y0109478*
X0639996*
Y0109532*
X0639888*
Y0109586*
X0639834*
Y010964*
X0639726*
Y0109694*
X0639672*
Y0109748*
X0639564*
Y0109802*
X063951*
Y0109856*
X0639402*
Y0109911*
X0639348*
Y0109965*
X063924*
Y0110019*
X0639131*
Y0110073*
X0639078*
Y0110127*
X0638969*
Y0110181*
X0638915*
Y0110235*
X0638807*
Y0110289*
X0638699*
Y0110343*
X0638645*
Y0110397*
X0638537*
Y0110451*
X0638429*
Y0110505*
X0638321*
Y0110559*
X0638267*
Y0110613*
X0638158*
Y0110668*
X063805*
Y0110722*
X0637942*
Y0110776*
X0637834*
Y011083*
X063778*
Y0110884*
X0637618*
Y0110938*
X0637564*
Y0110992*
X0637456*
Y0111046*
X0637293*
Y01111*
X0637185*
Y0111154*
X0637131*
Y0111208*
X0637023*
Y0111262*
X0636861*
Y0111316*
X0636753*
Y011137*
X0636645*
Y0111424*
X0636537*
Y0111478*
X0636428*
Y0111532*
X0636266*
Y0111586*
X0636158*
Y0111641*
X063605*
Y0111695*
X0635888*
Y0111749*
X063578*
Y0111803*
X0635617*
Y0111857*
X0635455*
Y0111911*
X0635347*
Y0111965*
X0635185*
Y0112019*
X0635023*
Y0112073*
X0634861*
Y0112127*
X0634753*
Y0112181*
X063459*
Y0112235*
X0634428*
Y0112289*
X0634212*
Y0112343*
X063405*
Y0112397*
X0633887*
Y0112452*
X0633671*
Y0112505*
X0633509*
Y011256*
X0633293*
Y0112614*
X0633077*
Y0112668*
X063286*
Y0112722*
X0632644*
Y0112776*
X0632374*
Y011283*
X0632103*
Y0112884*
X0631833*
Y0112938*
X0631509*
Y0112992*
X0631184*
Y0113046*
X0630752*
Y01131*
X0630319*
Y0113154*
X0629833*
Y0113208*
X0629022*
Y0113262*
G37*
G36*
X0621453Y00918D02*
X0621345D01*
Y0091746*
X0621291*
Y00918*
X0614804*
Y0091746*
X0614641*
Y0091692*
X0614479*
Y0091638*
X0614371*
Y0091584*
X0614317*
Y009153*
X0614263*
Y0091475*
X0614209*
Y0091421*
X0614155*
Y0091367*
X0614101*
Y0091313*
X0614047*
Y0091259*
X0613993*
Y0091205*
X0613939*
Y0091151*
X0613885*
Y0091097*
X0613831*
Y0091043*
X0613776*
Y0090989*
X0613722*
Y0090935*
X0613668*
Y0090881*
X0613614*
Y0090827*
X061356*
Y0090773*
X0613506*
Y0090719*
X0613452*
Y0090664*
X0613398*
Y009061*
X0613344*
Y0090556*
X061329*
Y0090502*
X0613236*
Y0090448*
X0613182*
Y0090394*
X0613128*
Y009034*
X0613074*
Y0090286*
X061302*
Y0090232*
X0612965*
Y0090178*
X0612912*
Y0090124*
X0612857*
Y009007*
Y0090016*
X0612803*
Y0089962*
Y0089908*
Y0089854*
Y0089799*
X0612749*
Y0089745*
Y0089691*
Y0089637*
Y0089583*
Y0089529*
Y0089475*
Y0089421*
Y0089367*
Y0089313*
Y0089259*
Y0089205*
Y0089151*
Y0089097*
Y0089043*
Y0088989*
Y0088934*
Y008888*
Y0088826*
Y0088772*
Y0088718*
Y0088664*
Y008861*
Y0088556*
Y0088502*
Y0088448*
Y0088394*
Y008834*
Y0088286*
Y0088232*
Y0088178*
Y0088124*
Y0088069*
Y0088016*
Y0087961*
Y0087907*
Y0087853*
Y0087799*
Y0087745*
Y0087691*
Y0087637*
Y0087583*
Y0087529*
Y0087475*
Y0087421*
Y0087367*
Y0087313*
Y0087259*
Y0087204*
Y0087151*
Y0087096*
Y0087042*
Y0086988*
Y0086934*
Y008688*
Y0086826*
Y0086772*
Y0086718*
Y0086664*
Y008661*
Y0086556*
Y0086502*
Y0086448*
Y0086394*
Y0086339*
Y0086286*
Y0086231*
Y0086177*
Y0086123*
Y0086069*
Y0086015*
Y0085961*
Y0085907*
Y0085853*
Y0085799*
Y0085745*
Y0085691*
Y0085637*
Y0085583*
Y0085529*
Y0085474*
Y0085421*
Y0085366*
Y0085312*
Y0085258*
Y0085204*
Y008515*
Y0085096*
Y0085042*
Y0084988*
Y0084934*
Y008488*
Y0084826*
Y0084772*
Y0084718*
Y0084664*
Y008461*
Y0084556*
Y0084501*
Y0084447*
Y0084393*
Y0084339*
Y0084285*
Y0084231*
Y0084177*
Y0084123*
Y0084069*
Y0084015*
Y0083961*
Y0083907*
Y0083853*
Y0083799*
Y0083745*
Y0083691*
Y0083636*
Y0083582*
Y0083528*
Y0083474*
Y008342*
Y0083366*
Y0083312*
Y0083258*
Y0083204*
Y008315*
Y0083096*
Y0083042*
Y0082988*
Y0082934*
Y008288*
Y0082825*
Y0082771*
Y0082717*
Y0082663*
Y0082609*
Y0082555*
Y0082501*
Y0082447*
Y0082393*
Y0082339*
Y0082285*
Y0082231*
Y0082177*
Y0082123*
Y0082069*
Y0082015*
Y008196*
X0612803*
Y0081906*
Y0081852*
Y0081798*
X0612857*
Y0081744*
Y008169*
X0612912*
Y0081636*
X0612965*
Y0081582*
X061302*
Y0081528*
X0613074*
Y0081474*
X0613128*
Y008142*
X0613182*
Y0081366*
X0613236*
Y0081312*
X061329*
Y0081258*
X0613344*
Y0081204*
X0613398*
Y008115*
X0613452*
Y0081095*
X0613506*
Y0081042*
X061356*
Y0080987*
X0613614*
Y0080933*
X0613668*
Y0080879*
X0613722*
Y0080825*
X0613776*
Y0080771*
X0613831*
Y0080717*
X0613885*
Y0080663*
X0613939*
Y0080609*
X0613993*
Y0080555*
X0614047*
Y0080501*
X0614101*
Y0080447*
X0614155*
Y0080393*
X0614209*
Y0080339*
X0614263*
Y0080285*
X0614317*
Y008023*
X0614371*
Y0080177*
X0614425*
Y0080122*
X0614533*
Y0080068*
X0614696*
Y0080014*
X0621561*
Y0080068*
X0621615*
Y0080122*
X0621669*
Y0080177*
X0621724*
Y008023*
Y0080285*
Y0080339*
Y0080393*
Y0080447*
Y0080501*
Y0080555*
Y0080609*
Y0080663*
Y0080717*
Y0080771*
Y0080825*
Y0080879*
Y0080933*
Y0080987*
Y0081042*
Y0081095*
Y008115*
Y0081204*
Y0081258*
Y0081312*
Y0081366*
Y008142*
Y0081474*
Y0081528*
Y0081582*
Y0081636*
Y008169*
Y0081744*
Y0081798*
Y0081852*
Y0081906*
Y008196*
Y0082015*
Y0082069*
Y0082123*
Y0082177*
Y0082231*
Y0082285*
Y0082339*
Y0082393*
Y0082447*
Y0082501*
Y0082555*
Y0082609*
Y0082663*
Y0082717*
X0621669*
Y0082771*
X0621615*
Y0082825*
X0621507*
Y008288*
X0615885*
Y0082934*
X0615777*
Y0082988*
Y0083042*
X0615723*
Y0083096*
Y008315*
Y0083204*
Y0083258*
Y0083312*
Y0083366*
Y008342*
Y0083474*
Y0083528*
Y0083582*
Y0083636*
Y0083691*
Y0083745*
Y0083799*
Y0083853*
Y0083907*
Y0083961*
Y0084015*
Y0084069*
Y0084123*
Y0084177*
Y0084231*
Y0084285*
Y0084339*
Y0084393*
Y0084447*
Y0084501*
Y0084556*
Y008461*
Y0084664*
Y0084718*
Y0084772*
Y0084826*
Y008488*
Y0084934*
Y0084988*
Y0085042*
Y0085096*
Y008515*
Y0085204*
Y0085258*
Y0085312*
Y0085366*
Y0085421*
Y0085474*
Y0085529*
Y0085583*
Y0085637*
Y0085691*
Y0085745*
Y0085799*
Y0085853*
Y0085907*
Y0085961*
Y0086015*
Y0086069*
Y0086123*
Y0086177*
Y0086231*
Y0086286*
Y0086339*
Y0086394*
Y0086448*
Y0086502*
Y0086556*
Y008661*
Y0086664*
Y0086718*
Y0086772*
Y0086826*
Y008688*
Y0086934*
Y0086988*
Y0087042*
Y0087096*
Y0087151*
Y0087204*
Y0087259*
Y0087313*
Y0087367*
Y0087421*
Y0087475*
Y0087529*
Y0087583*
Y0087637*
Y0087691*
Y0087745*
Y0087799*
Y0087853*
Y0087907*
Y0087961*
Y0088016*
Y0088069*
Y0088124*
Y0088178*
Y0088232*
Y0088286*
Y008834*
Y0088394*
Y0088448*
Y0088502*
Y0088556*
Y008861*
Y0088664*
Y0088718*
Y0088772*
X0615777*
Y0088826*
X0615831*
Y008888*
X0621183*
Y0088934*
X0621237*
Y008888*
X0621453*
Y0088934*
X0621615*
Y0088989*
X0621669*
Y0089043*
X0621724*
Y0089097*
Y0089151*
Y0089205*
Y0089259*
Y0089313*
Y0089367*
Y0089421*
Y0089475*
Y0089529*
Y0089583*
Y0089637*
Y0089691*
Y0089745*
Y0089799*
Y0089854*
Y0089908*
Y0089962*
Y0090016*
Y009007*
Y0090124*
Y0090178*
Y0090232*
Y0090286*
Y009034*
Y0090394*
Y0090448*
Y0090502*
Y0090556*
Y009061*
Y0090664*
Y0090719*
Y0090773*
Y0090827*
Y0090881*
Y0090935*
Y0090989*
Y0091043*
Y0091097*
Y0091151*
Y0091205*
Y0091259*
Y0091313*
Y0091367*
Y0091421*
Y0091475*
Y009153*
Y0091584*
Y0091638*
X0621669*
Y0091692*
X0621615*
Y0091746*
X0621453*
Y00918*
G37*
G36*
X0630914D02*
X0630157D01*
Y0091746*
X0630103*
Y0091692*
X0630049*
Y0091638*
X0629995*
Y0091584*
X0629941*
Y009153*
X0629887*
Y0091475*
X0629833*
Y0091421*
X0629779*
Y0091367*
X0629725*
Y0091313*
X0629671*
Y0091259*
X0629617*
Y0091205*
X0629563*
Y0091151*
X0629508*
Y0091097*
X0629454*
Y0091043*
X06294*
Y0090989*
X0629346*
Y0090935*
X0629292*
Y0090881*
X0629238*
Y0090827*
X0629184*
Y0090773*
X062913*
Y0090719*
X0629076*
Y0090664*
X0629022*
Y009061*
X0628968*
Y0090556*
X0628914*
Y0090502*
X062886*
Y0090448*
X0628806*
Y0090394*
X0628752*
Y009034*
X0628698*
Y0090286*
X0628644*
Y0090232*
X0628589*
Y0090178*
X0628535*
Y0090124*
X0628481*
Y009007*
X0628427*
Y0090016*
X0628373*
Y0089962*
X0628319*
Y0089908*
X0628265*
Y0089854*
X0628211*
Y0089799*
X0628157*
Y0089745*
X0628103*
Y0089691*
X0628049*
Y0089637*
X0627995*
Y0089583*
X0627941*
Y0089529*
X0627887*
Y0089475*
X0627833*
Y0089421*
X0627778*
Y0089367*
X0627725*
Y0089313*
X062767*
Y0089259*
X0627616*
Y0089205*
X0627562*
Y0089151*
X0629995*
Y0089097*
Y0089043*
Y0088989*
Y0088934*
Y008888*
Y0088826*
Y0088772*
Y0088718*
Y0088664*
Y008861*
Y0088556*
Y0088502*
Y0088448*
Y0088394*
Y008834*
Y0088286*
Y0088232*
Y0088178*
Y0088124*
Y0088069*
Y0088016*
Y0087961*
Y0087907*
Y0087853*
Y0087799*
Y0087745*
Y0087691*
Y0087637*
Y0087583*
Y0087529*
Y0087475*
Y0087421*
Y0087367*
Y0087313*
Y0087259*
Y0087204*
Y0087151*
Y0087096*
Y0087042*
Y0086988*
Y0086934*
Y008688*
Y0086826*
Y0086772*
Y0086718*
Y0086664*
Y008661*
Y0086556*
Y0086502*
Y0086448*
Y0086394*
Y0086339*
Y0086286*
Y0086231*
Y0086177*
X0626049*
Y0086231*
Y0086286*
Y0086339*
Y0086394*
Y0086448*
Y0086502*
Y0086556*
Y008661*
Y0086664*
Y0086718*
Y0086772*
Y0086826*
Y008688*
Y0086934*
Y0086988*
Y0087042*
Y0087096*
Y0087151*
Y0087204*
Y0087259*
Y0087313*
Y0087367*
X0625994*
Y0087313*
X062594*
Y0087259*
X0625886*
Y0087204*
X0625832*
Y0087151*
X0625778*
Y0087096*
X0625724*
Y0087042*
X062567*
Y0086988*
X0625616*
Y0086934*
X0625562*
Y008688*
X0625508*
Y0086826*
X0625454*
Y0086772*
X06254*
Y0086718*
X0625346*
Y0086664*
X0625292*
Y008661*
X0625238*
Y0086556*
X0625184*
Y0086502*
X062513*
Y0086448*
X0625075*
Y0086394*
X0625021*
Y0086339*
X0624967*
Y0086286*
X0624913*
Y0086231*
X0624859*
Y0086177*
X0624805*
Y0086123*
X0624751*
Y0086069*
X0624697*
Y0086015*
X0624643*
Y0085961*
X0624589*
Y0085907*
X0624535*
Y0085853*
X0624481*
Y0085799*
X0624427*
Y0085745*
X0624373*
Y0085691*
X0624319*
Y0085637*
X0624264*
Y0085583*
X062421*
Y0085529*
X0624156*
Y0085474*
X0624102*
Y0085421*
X0624048*
Y0085366*
X0623994*
Y0085312*
X062394*
Y0085258*
X0623886*
Y0085204*
X0623832*
Y008515*
X0623778*
Y0085096*
X0623724*
Y0085042*
X062367*
Y0084988*
X0623616*
Y0084934*
X0623562*
Y008488*
X0623508*
Y0084826*
X0623399*
Y0084772*
X0623345*
Y0084718*
X0623291*
Y0084664*
X0623237*
Y008461*
X0623183*
Y0084556*
X0623129*
Y0084501*
X0623075*
Y0084447*
Y0084393*
Y0084339*
Y0084285*
Y0084231*
Y0084177*
Y0084123*
Y0084069*
Y0084015*
Y0083961*
Y0083907*
Y0083853*
Y0083799*
Y0083745*
Y0083691*
Y0083636*
Y0083582*
Y0083528*
Y0083474*
Y008342*
Y0083366*
Y0083312*
Y0083258*
Y0083204*
Y008315*
Y0083096*
Y0083042*
Y0082988*
Y0082934*
Y008288*
Y0082825*
Y0082771*
Y0082717*
Y0082663*
Y0082609*
Y0082555*
Y0082501*
Y0082447*
Y0082393*
Y0082339*
Y0082285*
Y0082231*
Y0082177*
Y0082123*
Y0082069*
Y0082015*
Y008196*
Y0081906*
Y0081852*
Y0081798*
Y0081744*
Y008169*
Y0081636*
Y0081582*
Y0081528*
Y0081474*
Y008142*
Y0081366*
Y0081312*
Y0081258*
Y0081204*
Y008115*
Y0081095*
Y0081042*
Y0080987*
Y0080933*
Y0080879*
Y0080825*
Y0080771*
Y0080717*
Y0080663*
Y0080609*
Y0080555*
Y0080501*
Y0080447*
Y0080393*
Y0080339*
Y0080285*
Y008023*
Y0080177*
X0623129*
Y0080122*
X0623183*
Y0080068*
X0623291*
Y0080014*
X0625832*
Y0080068*
X062594*
Y0080122*
X0625994*
Y0080177*
Y008023*
X0626049*
Y0080285*
Y0080339*
Y0080393*
Y0080447*
Y0080501*
Y0080555*
Y0080609*
Y0080663*
Y0080717*
Y0080771*
Y0080825*
Y0080879*
Y0080933*
Y0080987*
Y0081042*
Y0081095*
Y008115*
Y0081204*
Y0081258*
Y0081312*
Y0081366*
Y008142*
Y0081474*
Y0081528*
Y0081582*
Y0081636*
Y008169*
Y0081744*
Y0081798*
Y0081852*
Y0081906*
Y008196*
Y0082015*
Y0082069*
Y0082123*
Y0082177*
Y0082231*
Y0082285*
Y0082339*
Y0082393*
Y0082447*
Y0082501*
Y0082555*
Y0082609*
Y0082663*
Y0082717*
Y0082771*
Y0082825*
Y008288*
Y0082934*
Y0082988*
Y0083042*
Y0083096*
Y008315*
Y0083204*
Y0083258*
Y0083312*
Y0083366*
Y008342*
Y0083474*
X0626103*
Y0083528*
Y0083582*
X0626211*
Y0083636*
X0629833*
Y0083582*
X0629941*
Y0083528*
Y0083474*
X0629995*
Y008342*
Y0083366*
Y0083312*
Y0083258*
Y0083204*
Y008315*
Y0083096*
Y0083042*
Y0082988*
Y0082934*
Y008288*
Y0082825*
Y0082771*
Y0082717*
Y0082663*
Y0082609*
Y0082555*
Y0082501*
Y0082447*
Y0082393*
Y0082339*
Y0082285*
Y0082231*
Y0082177*
Y0082123*
Y0082069*
Y0082015*
Y008196*
Y0081906*
Y0081852*
Y0081798*
Y0081744*
Y008169*
Y0081636*
Y0081582*
Y0081528*
Y0081474*
Y008142*
Y0081366*
Y0081312*
Y0081258*
Y0081204*
Y008115*
Y0081095*
Y0081042*
Y0080987*
Y0080933*
Y0080879*
Y0080825*
Y0080771*
Y0080717*
Y0080663*
Y0080609*
Y0080555*
Y0080501*
Y0080447*
Y0080393*
Y0080339*
Y0080285*
Y008023*
Y0080177*
X0630049*
Y0080122*
X0630103*
Y0080068*
X0630211*
Y0080014*
X0632752*
Y0080068*
X063286*
Y0080122*
X0632914*
Y0080177*
Y008023*
X0632969*
Y0080285*
Y0080339*
Y0080393*
Y0080447*
Y0080501*
Y0080555*
Y0080609*
Y0080663*
Y0080717*
Y0080771*
Y0080825*
Y0080879*
Y0080933*
Y0080987*
Y0081042*
Y0081095*
Y008115*
Y0081204*
Y0081258*
Y0081312*
Y0081366*
Y008142*
Y0081474*
Y0081528*
Y0081582*
Y0081636*
Y008169*
Y0081744*
Y0081798*
Y0081852*
Y0081906*
Y008196*
Y0082015*
Y0082069*
Y0082123*
Y0082177*
Y0082231*
Y0082285*
Y0082339*
Y0082393*
Y0082447*
Y0082501*
Y0082555*
Y0082609*
Y0082663*
Y0082717*
Y0082771*
Y0082825*
Y008288*
Y0082934*
Y0082988*
Y0083042*
Y0083096*
Y008315*
Y0083204*
Y0083258*
Y0083312*
Y0083366*
Y008342*
Y0083474*
Y0083528*
Y0083582*
Y0083636*
Y0083691*
Y0083745*
Y0083799*
Y0083853*
Y0083907*
Y0083961*
Y0084015*
Y0084069*
Y0084123*
Y0084177*
Y0084231*
Y0084285*
Y0084339*
Y0084393*
Y0084447*
Y0084501*
Y0084556*
Y008461*
Y0084664*
Y0084718*
Y0084772*
Y0084826*
Y008488*
Y0084934*
Y0084988*
Y0085042*
Y0085096*
Y008515*
Y0085204*
Y0085258*
Y0085312*
Y0085366*
Y0085421*
Y0085474*
Y0085529*
Y0085583*
Y0085637*
Y0085691*
Y0085745*
Y0085799*
Y0085853*
Y0085907*
Y0085961*
Y0086015*
Y0086069*
Y0086123*
Y0086177*
Y0086231*
Y0086286*
Y0086339*
Y0086394*
Y0086448*
Y0086502*
Y0086556*
Y008661*
Y0086664*
Y0086718*
Y0086772*
Y0086826*
Y008688*
Y0086934*
Y0086988*
Y0087042*
Y0087096*
Y0087151*
Y0087204*
Y0087259*
Y0087313*
Y0087367*
Y0087421*
Y0087475*
Y0087529*
Y0087583*
Y0087637*
Y0087691*
Y0087745*
Y0087799*
Y0087853*
Y0087907*
Y0087961*
Y0088016*
Y0088069*
Y0088124*
Y0088178*
Y0088232*
Y0088286*
Y008834*
Y0088394*
Y0088448*
Y0088502*
Y0088556*
Y008861*
Y0088664*
Y0088718*
Y0088772*
Y0088826*
Y008888*
Y0088934*
Y0088989*
Y0089043*
Y0089097*
Y0089151*
Y0089205*
Y0089259*
Y0089313*
Y0089367*
Y0089421*
Y0089475*
Y0089529*
Y0089583*
Y0089637*
Y0089691*
Y0089745*
X0632914*
Y0089799*
Y0089854*
Y0089908*
Y0089962*
X063286*
Y0090016*
Y009007*
Y0090124*
X0632806*
Y0090178*
X0632752*
Y0090232*
X0632698*
Y0090286*
X0632644*
Y009034*
X063259*
Y0090394*
X0632536*
Y0090448*
X0632482*
Y0090502*
X0632428*
Y0090556*
X0632374*
Y009061*
X063232*
Y0090664*
X0632266*
Y0090719*
X0632212*
Y0090773*
X0632158*
Y0090827*
X0632103*
Y0090881*
X0632049*
Y0090935*
X0631995*
Y0090989*
X0631941*
Y0091043*
X0631887*
Y0091097*
X0631833*
Y0091151*
X0631779*
Y0091205*
X0631725*
Y0091259*
X0631671*
Y0091313*
X0631617*
Y0091367*
X0631563*
Y0091421*
X0631509*
Y0091475*
X0631455*
Y009153*
X0631401*
Y0091584*
X0631347*
Y0091638*
X0631239*
Y0091692*
X063113*
Y0091746*
X0630914*
Y00918*
G37*
G36*
X0627184Y0110992D02*
X0626211D01*
Y0110938*
Y0110884*
Y011083*
Y0110776*
Y0110722*
Y0110668*
Y0110613*
Y0110559*
Y0110505*
Y0110451*
Y0110397*
Y0110343*
Y0110289*
Y0110235*
Y0110181*
Y0110127*
Y0110073*
Y0110019*
Y0109965*
Y0109911*
Y0109856*
Y0109802*
Y0109748*
Y0109694*
Y010964*
Y0109586*
Y0109532*
Y0109478*
Y0109424*
Y010937*
Y0109316*
Y0109262*
Y0109208*
Y0109154*
Y01091*
Y0109046*
Y0108992*
Y0108938*
Y0108883*
Y0108829*
Y0108775*
Y0108721*
Y0108667*
Y0108613*
Y0108559*
Y0108505*
Y0108451*
Y0108397*
Y0108343*
Y0108289*
Y0108235*
Y0108181*
Y0108126*
Y0108072*
Y0108018*
Y0107964*
Y010791*
Y0107856*
Y0107802*
Y0107748*
Y0107694*
Y010764*
Y0107586*
Y0107532*
Y0107478*
Y0107424*
Y010737*
Y0107316*
Y0107262*
Y0107208*
Y0107153*
Y0107099*
Y0107045*
Y0106991*
Y0106937*
Y0106883*
Y0106829*
Y0106775*
Y0106721*
Y0106667*
Y0106613*
Y0106559*
Y0106505*
Y0106451*
Y0106397*
Y0106342*
Y0106288*
Y0106234*
Y010618*
Y0106126*
Y0106072*
Y0106018*
Y0105964*
Y010591*
Y0105856*
Y0105802*
Y0105748*
Y0105694*
Y010564*
Y0105586*
Y0105532*
Y0105477*
Y0105423*
Y0105369*
Y0105315*
Y0105261*
Y0105207*
Y0105153*
Y0105099*
Y0105045*
Y0104991*
Y0104937*
Y0104883*
Y0104829*
Y0104775*
Y0104721*
Y0104667*
Y0104613*
Y0104558*
Y0104504*
Y010445*
Y0104396*
Y0104342*
Y0104288*
Y0104234*
Y010418*
Y0104126*
Y0104072*
Y0104018*
Y0103964*
Y010391*
Y0103856*
Y0103802*
Y0103747*
Y0103693*
Y0103639*
Y0103585*
Y0103531*
Y0103477*
Y0103423*
Y0103369*
Y0103315*
Y0103261*
Y0103207*
Y0103153*
Y0103099*
Y0103045*
Y0102991*
Y0102937*
Y0102883*
Y0102828*
Y0102774*
Y010272*
Y0102666*
Y0102612*
Y0102558*
Y0102504*
Y010245*
Y0102396*
Y0102342*
Y0102288*
Y0102234*
Y010218*
Y0102126*
Y0102072*
Y0102017*
Y0101963*
Y0101909*
Y0101855*
Y0101801*
Y0101747*
Y0101693*
Y0101639*
Y0101585*
Y0101531*
Y0101477*
Y0101423*
Y0101369*
Y0101315*
Y0101261*
Y0101207*
Y0101153*
Y0101099*
Y0101044*
Y010099*
Y0100936*
Y0100882*
Y0100828*
Y0100774*
Y010072*
Y0100666*
Y0100612*
Y0100558*
Y0100504*
Y010045*
Y0100396*
Y0100342*
Y0100287*
Y0100233*
Y0100179*
Y0100125*
Y0100071*
Y0100017*
Y0099963*
Y0099909*
Y0099855*
Y0099801*
Y0099747*
Y0099693*
Y0099639*
Y0099585*
Y0099531*
Y0099477*
Y0099423*
Y0099369*
Y0099314*
Y009926*
Y0099206*
Y0099152*
Y0099098*
Y0099044*
Y009899*
Y0098936*
Y0098882*
Y0098828*
Y0098774*
Y009872*
Y0098666*
Y0098612*
Y0098558*
Y0098504*
Y0098449*
Y0098395*
Y0098341*
Y0098287*
Y0098233*
Y0098179*
Y0098125*
Y0098071*
Y0098017*
Y0097963*
Y0097909*
Y0097855*
Y0097801*
Y0097747*
Y0097693*
Y0097638*
Y0097584*
Y009753*
Y0097476*
Y0097422*
Y0097368*
Y0097314*
Y009726*
Y0097206*
Y0097152*
Y0097098*
Y0097044*
Y009699*
Y0096936*
Y0096882*
Y0096828*
Y0096773*
Y0096719*
Y0096665*
Y0096611*
Y0096557*
Y0096503*
Y0096449*
Y0096395*
Y0096341*
Y0096287*
Y0096233*
Y0096179*
Y0096125*
Y0096071*
Y0096017*
Y0095963*
Y0095908*
Y0095854*
Y00958*
Y0095746*
Y0095692*
Y0095638*
Y0095584*
Y009553*
Y0095476*
Y0095422*
Y0095368*
Y0095314*
Y009526*
Y0095206*
Y0095152*
Y0095098*
Y0095043*
Y009499*
Y0094935*
Y0094881*
Y0094827*
Y0094773*
Y0094719*
Y0094665*
Y0094611*
Y0094557*
Y0094503*
Y0094449*
Y0094395*
Y0094341*
Y0094287*
Y0094233*
Y0094178*
Y0094125*
Y009407*
Y0094016*
Y0093962*
Y0093908*
Y0093854*
Y00938*
Y0093746*
Y0093692*
Y0093638*
Y0093584*
Y009353*
Y0093476*
Y0093422*
Y0093368*
Y0093313*
Y009326*
Y0093205*
Y0093151*
Y0093097*
X0626157*
Y0093043*
X0626103*
Y0092989*
X0626049*
Y0092935*
X0625994*
Y0092881*
X062594*
Y0092827*
X0625886*
Y0092773*
X0625832*
Y0092719*
X0625778*
Y0092665*
X0625724*
Y0092611*
X062567*
Y0092557*
X0625616*
Y0092503*
X0625562*
Y0092449*
X0625508*
Y0092395*
X0625454*
Y009234*
X06254*
Y0092286*
X0625346*
Y0092232*
X0625292*
Y0092178*
X0625184*
Y0092124*
X062513*
Y009207*
X0625075*
Y0092016*
X0625021*
Y0091962*
X0624967*
Y0091908*
X0624913*
Y0091854*
X0624859*
Y00918*
X0624805*
Y0091746*
X0624751*
Y0091692*
X0624697*
Y0091638*
X0624643*
Y0091584*
X0624589*
Y009153*
X0624535*
Y0091475*
X0624481*
Y0091421*
X0624427*
Y0091367*
X0624373*
Y0091313*
X0624319*
Y0091259*
X0624264*
Y0091205*
X062421*
Y0091151*
X0624156*
Y0091097*
X0624102*
Y0091043*
X0624048*
Y0090989*
X0623994*
Y0090935*
X062394*
Y0090881*
X0623886*
Y0090827*
X0623832*
Y0090773*
X0623778*
Y0090719*
X0623724*
Y0090664*
X062367*
Y009061*
X0623616*
Y0090556*
X0623562*
Y0090502*
X0623508*
Y0090448*
X0623454*
Y0090394*
X0623399*
Y009034*
X0623345*
Y0090286*
X0623291*
Y0090232*
X0623237*
Y0090178*
X0623183*
Y0090124*
X0623129*
Y009007*
X0623075*
Y0090016*
X0623021*
Y0089962*
X0622967*
Y0089908*
X0622913*
Y0089854*
X0622859*
Y0089799*
X0622805*
Y0089745*
X0622751*
Y0089691*
X0622697*
Y0089637*
X0622643*
Y0089583*
X0622589*
Y0089529*
X0622535*
Y0089475*
X062248*
Y0089421*
X0622426*
Y0089367*
X0622372*
Y0089313*
X0622318*
Y0089259*
X0622264*
Y0089205*
X062221*
Y0089151*
X0622156*
Y0089097*
X0622102*
Y0089043*
X0622048*
Y0088989*
X0621994*
Y0088934*
X062194*
Y008888*
X0621886*
Y0088826*
X0621832*
Y0088772*
X0621778*
Y0088718*
X0621724*
Y0088664*
X0621669*
Y008861*
X0621615*
Y0088556*
X0621507*
Y0088502*
X0621453*
Y0088448*
X0621399*
Y0088394*
X0621345*
Y008834*
X0621291*
Y0088286*
X0621237*
Y0088232*
X0621183*
Y0088178*
X0621129*
Y0088124*
X0621075*
Y0088069*
X0621021*
Y0088016*
X0620967*
Y0087961*
X0620913*
Y0087907*
X0620859*
Y0087853*
X0620805*
Y0087799*
X0620751*
Y0087745*
X0620696*
Y0087691*
X0620642*
Y0087637*
Y0087583*
X0620588*
Y0087529*
X0620534*
Y0087475*
Y0087421*
X062048*
Y0087367*
Y0087313*
X0620426*
Y0087259*
Y0087204*
Y0087151*
Y0087096*
Y0087042*
Y0086988*
Y0086934*
Y008688*
Y0086826*
Y0086772*
Y0086718*
Y0086664*
Y008661*
Y0086556*
Y0086502*
Y0086448*
Y0086394*
Y0086339*
Y0086286*
Y0086231*
Y0086177*
Y0086123*
Y0086069*
Y0086015*
Y0085961*
Y0085907*
Y0085853*
Y0085799*
Y0085745*
Y0085691*
Y0085637*
Y0085583*
Y0085529*
Y0085474*
Y0085421*
Y0085366*
Y0085312*
Y0085258*
Y0085204*
Y008515*
Y0085096*
Y0085042*
Y0084988*
Y0084934*
Y008488*
X062048*
Y0084826*
X0620534*
Y0084772*
Y0084718*
X0620588*
Y0084664*
X0620642*
Y008461*
Y0084556*
X0620696*
Y0084501*
X0620751*
Y0084447*
X0620805*
Y0084393*
X0620859*
Y0084339*
X0620913*
Y0084285*
X0620967*
Y0084231*
X0621021*
Y0084177*
X0621075*
Y0084123*
X0621129*
Y0084069*
X0621237*
Y0084123*
X0621291*
Y0084177*
X0621345*
Y0084231*
X0621399*
Y0084285*
X0621453*
Y0084339*
X0621507*
Y0084393*
X0621561*
Y0084447*
X0621615*
Y0084501*
X0621669*
Y0084556*
X0621724*
Y008461*
X0621778*
Y0084664*
X0621832*
Y0084718*
X0621886*
Y0084772*
X062194*
Y0084826*
X0621994*
Y008488*
X0622048*
Y0084934*
X0622102*
Y0084988*
X0622156*
Y0085042*
X062221*
Y0085096*
X0622264*
Y008515*
X0622318*
Y0085204*
X0622372*
Y0085258*
X0622426*
Y0085312*
X062248*
Y0085366*
X0622589*
Y0085421*
X0622643*
Y0085474*
X0622697*
Y0085529*
X0622751*
Y0085583*
X0622805*
Y0085637*
X0622859*
Y0085691*
X0622913*
Y0085745*
X0622967*
Y0085799*
X0623021*
Y0085853*
X0623075*
Y0085907*
X0623129*
Y0085961*
X0623183*
Y0086015*
X0623237*
Y0086069*
X0623291*
Y0086123*
X0623345*
Y0086177*
X0623399*
Y0086231*
X0623454*
Y0086286*
X0623508*
Y0086339*
X0623562*
Y0086394*
X0623616*
Y0086448*
X062367*
Y0086502*
X0623724*
Y0086556*
X0623778*
Y008661*
X0623832*
Y0086664*
X0623886*
Y0086718*
X062394*
Y0086772*
X0623994*
Y0086826*
X0624048*
Y008688*
X0624102*
Y0086934*
X0624156*
Y0086988*
X062421*
Y0087042*
X0624264*
Y0087096*
X0624319*
Y0087151*
X0624373*
Y0087204*
X0624427*
Y0087259*
X0624481*
Y0087313*
X0624535*
Y0087367*
X0624589*
Y0087421*
X0624643*
Y0087475*
X0624697*
Y0087529*
X0624751*
Y0087583*
X0624805*
Y0087637*
X0624859*
Y0087691*
X0624913*
Y0087745*
X0624967*
Y0087799*
X0625021*
Y0087853*
X0625075*
Y0087907*
X062513*
Y0087961*
X0625184*
Y0088016*
X0625238*
Y0088069*
X0625292*
Y0088124*
X0625346*
Y0088178*
X06254*
Y0088232*
X0625454*
Y0088286*
X0625508*
Y008834*
X0625562*
Y0088394*
X0625616*
Y0088448*
X062567*
Y0088502*
X0625724*
Y0088556*
X0625778*
Y008861*
X0625832*
Y0088664*
X0625886*
Y0088718*
X062594*
Y0088772*
X0625994*
Y0088826*
X0626049*
Y008888*
X0626103*
Y0088934*
X0626157*
Y0088989*
X0626211*
Y0089043*
X0626265*
Y0089097*
X0626319*
Y0089151*
X0626373*
Y0089205*
X0626427*
Y0089259*
X0626481*
Y0089313*
X0626535*
Y0089367*
X0626589*
Y0089421*
X0626643*
Y0089475*
X0626697*
Y0089529*
X0626751*
Y0089583*
X0626805*
Y0089637*
X062686*
Y0089691*
X0626913*
Y0089745*
X0626968*
Y0089799*
X0627022*
Y0089854*
X0627076*
Y0089908*
X0627184*
Y0089962*
X0627238*
Y0090016*
X0627292*
Y009007*
X0627346*
Y0090124*
X06274*
Y0090178*
X0627454*
Y0090232*
X0627508*
Y0090286*
X0627562*
Y009034*
X0627616*
Y0090394*
X062767*
Y0090448*
X0627725*
Y0090502*
X0627778*
Y0090556*
X0627833*
Y009061*
X0627887*
Y0090664*
X0627941*
Y0090719*
X0627995*
Y0090773*
X0628049*
Y0090827*
X0628103*
Y0090881*
X0628157*
Y0090935*
X0628211*
Y0090989*
X0628265*
Y0091043*
X0628319*
Y0091097*
X0628373*
Y0091151*
X0628427*
Y0091205*
X0628481*
Y0091259*
X0628535*
Y0091313*
X0628589*
Y0091367*
X0628644*
Y0091421*
X0628698*
Y0091475*
X0628752*
Y009153*
X0628806*
Y0091584*
Y0091638*
X062886*
Y0091692*
X0628914*
Y0091746*
Y00918*
X0628968*
Y0091854*
Y0091908*
X0629022*
Y0091962*
Y0092016*
X0629076*
Y009207*
Y0092124*
Y0092178*
Y0092232*
X062913*
Y0092286*
Y009234*
Y0092395*
Y0092449*
Y0092503*
Y0092557*
Y0092611*
Y0092665*
Y0092719*
Y0092773*
Y0092827*
Y0092881*
Y0092935*
Y0092989*
Y0093043*
Y0093097*
Y0093151*
Y0093205*
Y009326*
Y0093313*
Y0093368*
Y0093422*
Y0093476*
Y009353*
Y0093584*
Y0093638*
Y0093692*
Y0093746*
Y00938*
Y0093854*
Y0093908*
Y0093962*
Y0094016*
Y009407*
Y0094125*
Y0094178*
Y0094233*
Y0094287*
Y0094341*
Y0094395*
Y0094449*
Y0094503*
Y0094557*
Y0094611*
Y0094665*
Y0094719*
Y0094773*
Y0094827*
Y0094881*
Y0094935*
Y009499*
Y0095043*
Y0095098*
Y0095152*
Y0095206*
Y009526*
Y0095314*
Y0095368*
Y0095422*
Y0095476*
Y009553*
Y0095584*
Y0095638*
Y0095692*
Y0095746*
Y00958*
Y0095854*
Y0095908*
Y0095963*
Y0096017*
Y0096071*
Y0096125*
Y0096179*
Y0096233*
Y0096287*
Y0096341*
Y0096395*
Y0096449*
Y0096503*
Y0096557*
Y0096611*
Y0096665*
Y0096719*
Y0096773*
Y0096828*
Y0096882*
Y0096936*
Y009699*
Y0097044*
Y0097098*
Y0097152*
Y0097206*
Y009726*
Y0097314*
Y0097368*
Y0097422*
Y0097476*
Y009753*
Y0097584*
Y0097638*
Y0097693*
Y0097747*
Y0097801*
Y0097855*
Y0097909*
Y0097963*
Y0098017*
Y0098071*
Y0098125*
Y0098179*
Y0098233*
Y0098287*
Y0098341*
Y0098395*
Y0098449*
Y0098504*
Y0098558*
Y0098612*
Y0098666*
Y009872*
Y0098774*
Y0098828*
Y0098882*
Y0098936*
Y009899*
Y0099044*
Y0099098*
Y0099152*
Y0099206*
Y009926*
Y0099314*
Y0099369*
Y0099423*
Y0099477*
Y0099531*
Y0099585*
Y0099639*
Y0099693*
Y0099747*
Y0099801*
Y0099855*
Y0099909*
Y0099963*
Y0100017*
Y0100071*
Y0100125*
Y0100179*
Y0100233*
Y0100287*
Y0100342*
Y0100396*
Y010045*
Y0100504*
Y0100558*
Y0100612*
Y0100666*
Y010072*
Y0100774*
Y0100828*
Y0100882*
Y0100936*
Y010099*
Y0101044*
Y0101099*
Y0101153*
Y0101207*
Y0101261*
Y0101315*
Y0101369*
Y0101423*
Y0101477*
Y0101531*
Y0101585*
Y0101639*
Y0101693*
Y0101747*
Y0101801*
Y0101855*
Y0101909*
Y0101963*
Y0102017*
Y0102072*
Y0102126*
Y010218*
Y0102234*
Y0102288*
Y0102342*
Y0102396*
Y010245*
Y0102504*
Y0102558*
Y0102612*
Y0102666*
Y010272*
Y0102774*
Y0102828*
Y0102883*
Y0102937*
Y0102991*
Y0103045*
Y0103099*
Y0103153*
Y0103207*
Y0103261*
Y0103315*
Y0103369*
Y0103423*
Y0103477*
Y0103531*
Y0103585*
Y0103639*
Y0103693*
Y0103747*
Y0103802*
Y0103856*
Y010391*
Y0103964*
Y0104018*
Y0104072*
Y0104126*
Y010418*
Y0104234*
Y0104288*
Y0104342*
Y0104396*
Y010445*
Y0104504*
Y0104558*
Y0104613*
Y0104667*
Y0104721*
Y0104775*
Y0104829*
Y0104883*
Y0104937*
Y0104991*
Y0105045*
Y0105099*
Y0105153*
Y0105207*
Y0105261*
Y0105315*
Y0105369*
Y0105423*
Y0105477*
Y0105532*
Y0105586*
Y010564*
Y0105694*
Y0105748*
Y0105802*
Y0105856*
Y010591*
Y0105964*
Y0106018*
Y0106072*
Y0106126*
Y010618*
Y0106234*
Y0106288*
Y0106342*
Y0106397*
Y0106451*
Y0106505*
Y0106559*
Y0106613*
Y0106667*
Y0106721*
Y0106775*
Y0106829*
Y0106883*
Y0106937*
Y0106991*
Y0107045*
Y0107099*
Y0107153*
Y0107208*
Y0107262*
Y0107316*
Y010737*
Y0107424*
Y0107478*
Y0107532*
Y0107586*
Y010764*
Y0107694*
Y0107748*
Y0107802*
Y0107856*
Y010791*
Y0107964*
Y0108018*
Y0108072*
Y0108126*
Y0108181*
Y0108235*
Y0108289*
Y0108343*
Y0108397*
Y0108451*
Y0108505*
Y0108559*
Y0108613*
Y0108667*
Y0108721*
Y0108775*
Y0108829*
Y0108883*
Y0108938*
Y0108992*
Y0109046*
X0629076*
Y01091*
Y0109154*
Y0109208*
Y0109262*
X0629022*
Y0109316*
Y010937*
X0628968*
Y0109424*
X0628914*
Y0109478*
X062886*
Y0109532*
X0628806*
Y0109586*
X0628752*
Y010964*
X0628698*
Y0109694*
X0628644*
Y0109748*
X0628589*
Y0109802*
X0628535*
Y0109856*
X0628481*
Y0109911*
X0628427*
Y0109965*
X0628373*
Y0110019*
X0628319*
Y0110073*
X0628265*
Y0110127*
X0628211*
Y0110181*
X0628157*
Y0110235*
X0628103*
Y0110289*
X0628049*
Y0110343*
X0627995*
Y0110397*
X0627941*
Y0110451*
X0627887*
Y0110505*
X0627833*
Y0110559*
X0627778*
Y0110613*
X0627725*
Y0110668*
X062767*
Y0110722*
X0627616*
Y0110776*
X0627562*
Y011083*
X0627508*
Y0110884*
X06274*
Y0110938*
X0627184*
Y0110992*
G37*
G36*
X065335Y00918D02*
X0645889D01*
Y0091746*
X0645781*
Y0091692*
X0645727*
Y0091638*
X0645673*
Y0091584*
X0645619*
Y009153*
Y0091475*
Y0091421*
Y0091367*
Y0091313*
Y0091259*
Y0091205*
Y0091151*
Y0091097*
Y0091043*
Y0090989*
Y0090935*
Y0090881*
Y0090827*
Y0090773*
Y0090719*
Y0090664*
Y009061*
Y0090556*
Y0090502*
Y0090448*
Y0090394*
Y009034*
Y0090286*
Y0090232*
Y0090178*
Y0090124*
Y009007*
Y0090016*
Y0089962*
Y0089908*
Y0089854*
Y0089799*
Y0089745*
Y0089691*
Y0089637*
Y0089583*
Y0089529*
Y0089475*
Y0089421*
Y0089367*
Y0089313*
Y0089259*
Y0089205*
Y0089151*
Y0089097*
Y0089043*
Y0088989*
Y0088934*
Y008888*
Y0088826*
Y0088772*
Y0088718*
Y0088664*
Y008861*
Y0088556*
Y0088502*
Y0088448*
Y0088394*
Y008834*
Y0088286*
Y0088232*
Y0088178*
Y0088124*
Y0088069*
Y0088016*
Y0087961*
Y0087907*
Y0087853*
Y0087799*
Y0087745*
Y0087691*
Y0087637*
Y0087583*
Y0087529*
Y0087475*
Y0087421*
Y0087367*
Y0087313*
Y0087259*
Y0087204*
Y0087151*
Y0087096*
Y0087042*
Y0086988*
Y0086934*
Y008688*
Y0086826*
Y0086772*
Y0086718*
Y0086664*
Y008661*
Y0086556*
Y0086502*
Y0086448*
Y0086394*
Y0086339*
Y0086286*
Y0086231*
Y0086177*
Y0086123*
Y0086069*
Y0086015*
Y0085961*
Y0085907*
Y0085853*
Y0085799*
Y0085745*
Y0085691*
Y0085637*
Y0085583*
Y0085529*
Y0085474*
Y0085421*
Y0085366*
Y0085312*
Y0085258*
Y0085204*
Y008515*
Y0085096*
Y0085042*
Y0084988*
Y0084934*
Y008488*
Y0084826*
Y0084772*
Y0084718*
Y0084664*
Y008461*
Y0084556*
Y0084501*
Y0084447*
Y0084393*
Y0084339*
Y0084285*
Y0084231*
Y0084177*
Y0084123*
Y0084069*
Y0084015*
Y0083961*
Y0083907*
Y0083853*
Y0083799*
Y0083745*
Y0083691*
Y0083636*
Y0083582*
Y0083528*
Y0083474*
Y008342*
Y0083366*
Y0083312*
Y0083258*
Y0083204*
Y008315*
Y0083096*
Y0083042*
Y0082988*
Y0082934*
Y008288*
Y0082825*
Y0082771*
Y0082717*
Y0082663*
Y0082609*
Y0082555*
Y0082501*
Y0082447*
Y0082393*
Y0082339*
Y0082285*
Y0082231*
Y0082177*
Y0082123*
Y0082069*
Y0082015*
Y008196*
Y0081906*
Y0081852*
Y0081798*
Y0081744*
Y008169*
Y0081636*
Y0081582*
Y0081528*
Y0081474*
Y008142*
Y0081366*
Y0081312*
Y0081258*
Y0081204*
Y008115*
Y0081095*
Y0081042*
Y0080987*
Y0080933*
Y0080879*
Y0080825*
Y0080771*
Y0080717*
Y0080663*
Y0080609*
Y0080555*
Y0080501*
Y0080447*
Y0080393*
Y0080339*
Y0080285*
Y008023*
Y0080177*
X0645673*
Y0080122*
X0645727*
Y0080068*
X0645781*
Y0080014*
X0653512*
Y0080068*
X0653728*
Y0080122*
X0653836*
Y0080177*
X0653891*
Y008023*
X0653944*
Y0080285*
X0653999*
Y0080339*
X0654053*
Y0080393*
X0654107*
Y0080447*
X0654161*
Y0080501*
X0654215*
Y0080555*
X0654269*
Y0080609*
X0654323*
Y0080663*
X0654377*
Y0080717*
X0654431*
Y0080771*
X0654485*
Y0080825*
X0654539*
Y0080879*
X0654593*
Y0080933*
X0654647*
Y0080987*
X0654701*
Y0081042*
X0654755*
Y0081095*
X065481*
Y008115*
X0654864*
Y0081204*
X0654918*
Y0081258*
X0654972*
Y0081312*
X0655026*
Y0081366*
X065508*
Y008142*
X0655134*
Y0081474*
X0655188*
Y0081528*
X0655242*
Y0081582*
X0655296*
Y0081636*
X065535*
Y008169*
X0655404*
Y0081744*
Y0081798*
Y0081852*
X0655458*
Y0081906*
Y008196*
Y0082015*
Y0082069*
X0655512*
Y0082123*
Y0082177*
Y0082231*
Y0082285*
Y0082339*
Y0082393*
Y0082447*
Y0082501*
Y0082555*
Y0082609*
Y0082663*
Y0082717*
Y0082771*
Y0082825*
Y008288*
Y0082934*
Y0082988*
Y0083042*
Y0083096*
Y008315*
Y0083204*
Y0083258*
Y0083312*
Y0083366*
Y008342*
Y0083474*
Y0083528*
Y0083582*
Y0083636*
Y0083691*
Y0083745*
Y0083799*
Y0083853*
Y0083907*
Y0083961*
Y0084015*
Y0084069*
Y0084123*
Y0084177*
Y0084231*
Y0084285*
Y0084339*
Y0084393*
Y0084447*
Y0084501*
Y0084556*
Y008461*
Y0084664*
Y0084718*
Y0084772*
Y0084826*
Y008488*
Y0084934*
Y0084988*
Y0085042*
Y0085096*
Y008515*
Y0085204*
Y0085258*
Y0085312*
Y0085366*
Y0085421*
Y0085474*
Y0085529*
Y0085583*
Y0085637*
Y0085691*
Y0085745*
Y0085799*
Y0085853*
Y0085907*
Y0085961*
Y0086015*
Y0086069*
Y0086123*
Y0086177*
Y0086231*
Y0086286*
Y0086339*
Y0086394*
Y0086448*
Y0086502*
Y0086556*
Y008661*
Y0086664*
Y0086718*
Y0086772*
Y0086826*
Y008688*
Y0086934*
Y0086988*
Y0087042*
Y0087096*
Y0087151*
Y0087204*
Y0087259*
Y0087313*
Y0087367*
Y0087421*
Y0087475*
Y0087529*
Y0087583*
Y0087637*
Y0087691*
Y0087745*
Y0087799*
Y0087853*
Y0087907*
Y0087961*
Y0088016*
Y0088069*
Y0088124*
Y0088178*
Y0088232*
Y0088286*
Y008834*
Y0088394*
Y0088448*
Y0088502*
Y0088556*
Y008861*
Y0088664*
Y0088718*
Y0088772*
Y0088826*
Y008888*
Y0088934*
Y0088989*
Y0089043*
Y0089097*
Y0089151*
Y0089205*
Y0089259*
Y0089313*
Y0089367*
Y0089421*
Y0089475*
Y0089529*
Y0089583*
Y0089637*
Y0089691*
Y0089745*
X0655458*
Y0089799*
Y0089854*
Y0089908*
Y0089962*
X0655404*
Y0090016*
Y009007*
X065535*
Y0090124*
X0655296*
Y0090178*
X0655242*
Y0090232*
X0655188*
Y0090286*
X0655134*
Y009034*
X065508*
Y0090394*
X0655026*
Y0090448*
X0654972*
Y0090502*
X0654918*
Y0090556*
X0654864*
Y009061*
X065481*
Y0090664*
X0654755*
Y0090719*
X0654701*
Y0090773*
X0654647*
Y0090827*
X0654593*
Y0090881*
X0654539*
Y0090935*
X0654485*
Y0090989*
X0654431*
Y0091043*
X0654377*
Y0091097*
X0654323*
Y0091151*
X0654269*
Y0091205*
X0654215*
Y0091259*
X0654161*
Y0091313*
X0654107*
Y0091367*
X0654053*
Y0091421*
X0653999*
Y0091475*
X0653944*
Y009153*
X0653891*
Y0091584*
X0653836*
Y0091638*
X0653782*
Y0091692*
X065362*
Y0091746*
X065335*
Y00918*
G37*
G36*
X0641835D02*
X0634374D01*
Y0091746*
X0634266*
Y0091692*
X0634212*
Y0091638*
X0634158*
Y0091584*
Y009153*
Y0091475*
X0634104*
Y0091421*
Y0091367*
Y0091313*
Y0091259*
Y0091205*
Y0091151*
Y0091097*
Y0091043*
Y0090989*
Y0090935*
Y0090881*
Y0090827*
Y0090773*
Y0090719*
Y0090664*
Y009061*
Y0090556*
Y0090502*
Y0090448*
Y0090394*
Y009034*
Y0090286*
Y0090232*
Y0090178*
Y0090124*
Y009007*
Y0090016*
Y0089962*
Y0089908*
Y0089854*
Y0089799*
Y0089745*
Y0089691*
Y0089637*
Y0089583*
Y0089529*
Y0089475*
Y0089421*
Y0089367*
Y0089313*
Y0089259*
Y0089205*
Y0089151*
Y0089097*
Y0089043*
Y0088989*
Y0088934*
Y008888*
Y0088826*
Y0088772*
Y0088718*
Y0088664*
Y008861*
Y0088556*
Y0088502*
Y0088448*
Y0088394*
Y008834*
Y0088286*
Y0088232*
Y0088178*
Y0088124*
Y0088069*
Y0088016*
Y0087961*
Y0087907*
Y0087853*
Y0087799*
Y0087745*
Y0087691*
Y0087637*
Y0087583*
Y0087529*
Y0087475*
Y0087421*
Y0087367*
Y0087313*
Y0087259*
Y0087204*
Y0087151*
Y0087096*
Y0087042*
Y0086988*
Y0086934*
Y008688*
Y0086826*
Y0086772*
Y0086718*
Y0086664*
Y008661*
Y0086556*
Y0086502*
Y0086448*
Y0086394*
Y0086339*
Y0086286*
Y0086231*
Y0086177*
Y0086123*
Y0086069*
Y0086015*
Y0085961*
Y0085907*
Y0085853*
Y0085799*
Y0085745*
Y0085691*
Y0085637*
Y0085583*
Y0085529*
Y0085474*
Y0085421*
Y0085366*
Y0085312*
Y0085258*
Y0085204*
Y008515*
Y0085096*
Y0085042*
Y0084988*
Y0084934*
Y008488*
Y0084826*
Y0084772*
Y0084718*
Y0084664*
Y008461*
Y0084556*
Y0084501*
Y0084447*
Y0084393*
Y0084339*
Y0084285*
Y0084231*
Y0084177*
Y0084123*
Y0084069*
Y0084015*
Y0083961*
Y0083907*
Y0083853*
Y0083799*
Y0083745*
Y0083691*
Y0083636*
Y0083582*
Y0083528*
Y0083474*
Y008342*
Y0083366*
Y0083312*
Y0083258*
Y0083204*
Y008315*
Y0083096*
Y0083042*
Y0082988*
Y0082934*
Y008288*
Y0082825*
Y0082771*
Y0082717*
Y0082663*
Y0082609*
Y0082555*
Y0082501*
Y0082447*
Y0082393*
Y0082339*
Y0082285*
Y0082231*
Y0082177*
Y0082123*
Y0082069*
Y0082015*
Y008196*
Y0081906*
Y0081852*
Y0081798*
Y0081744*
Y008169*
Y0081636*
Y0081582*
Y0081528*
Y0081474*
Y008142*
Y0081366*
Y0081312*
Y0081258*
Y0081204*
Y008115*
Y0081095*
Y0081042*
Y0080987*
Y0080933*
Y0080879*
Y0080825*
Y0080771*
Y0080717*
Y0080663*
Y0080609*
Y0080555*
Y0080501*
Y0080447*
Y0080393*
X0634158*
Y0080339*
X0634104*
Y0080285*
X0634158*
Y008023*
Y0080177*
Y0080122*
X0634212*
Y0080068*
X063432*
Y0080014*
X0636969*
Y0080068*
X0637023*
Y0080122*
X0637077*
Y0080177*
Y008023*
Y0080285*
X0637131*
Y0080339*
Y0080393*
Y0080447*
Y0080501*
Y0080555*
Y0080609*
Y0080663*
Y0080717*
Y0080771*
Y0080825*
Y0080879*
Y0080933*
Y0080987*
Y0081042*
Y0081095*
Y008115*
Y0081204*
Y0081258*
Y0081312*
Y0081366*
Y008142*
Y0081474*
Y0081528*
Y0081582*
Y0081636*
Y008169*
Y0081744*
Y0081798*
Y0081852*
Y0081906*
Y008196*
Y0082015*
Y0082069*
Y0082123*
Y0082177*
Y0082231*
Y0082285*
Y0082339*
Y0082393*
Y0082447*
Y0082501*
Y0082555*
Y0082609*
Y0082663*
Y0082717*
Y0082771*
Y0082825*
Y008288*
Y0082934*
Y0082988*
Y0083042*
Y0083096*
Y008315*
Y0083204*
X0637077*
Y0083258*
X0637131*
Y0083312*
Y0083366*
Y008342*
Y0083474*
Y0083528*
X0639186*
Y0083474*
Y008342*
X063924*
Y0083366*
Y0083312*
X0639294*
Y0083258*
X0639348*
Y0083204*
Y008315*
X0639402*
Y0083096*
Y0083042*
X0639456*
Y0082988*
X063951*
Y0082934*
Y008288*
X0639564*
Y0082825*
Y0082771*
X0639618*
Y0082717*
Y0082663*
X0639672*
Y0082609*
X0639726*
Y0082555*
Y0082501*
X063978*
Y0082447*
Y0082393*
X0639834*
Y0082339*
X0639888*
Y0082285*
Y0082231*
X0639943*
Y0082177*
Y0082123*
X0639996*
Y0082069*
X0640051*
Y0082015*
Y008196*
X0640105*
Y0081906*
Y0081852*
X0640159*
Y0081798*
Y0081744*
X0640213*
Y008169*
X0640267*
Y0081636*
Y0081582*
X0640321*
Y0081528*
Y0081474*
X0640375*
Y008142*
X0640429*
Y0081366*
Y0081312*
X0640483*
Y0081258*
Y0081204*
X0640537*
Y008115*
X0640591*
Y0081095*
Y0081042*
X0640645*
Y0080987*
Y0080933*
X0640699*
Y0080879*
X0640753*
Y0080825*
Y0080771*
X0640807*
Y0080717*
Y0080663*
X0640862*
Y0080609*
Y0080555*
X0640916*
Y0080501*
X064097*
Y0080447*
Y0080393*
X0641024*
Y0080339*
Y0080285*
X0641078*
Y008023*
X0641132*
Y0080177*
X0641186*
Y0080122*
X064124*
Y0080068*
X0641348*
Y0080014*
X0644376*
Y0080068*
X064443*
Y0080122*
Y0080177*
Y008023*
Y0080285*
X0644376*
Y0080339*
X0644321*
Y0080393*
Y0080447*
X0644267*
Y0080501*
Y0080555*
X0644213*
Y0080609*
X0644159*
Y0080663*
Y0080717*
X0644105*
Y0080771*
Y0080825*
X0644051*
Y0080879*
X0643997*
Y0080933*
Y0080987*
X0643943*
Y0081042*
Y0081095*
X0643889*
Y008115*
X0643835*
Y0081204*
Y0081258*
X0643781*
Y0081312*
Y0081366*
X0643727*
Y008142*
X0643673*
Y0081474*
Y0081528*
X0643619*
Y0081582*
Y0081636*
X0643565*
Y008169*
X0643511*
Y0081744*
Y0081798*
X0643457*
Y0081852*
Y0081906*
X0643402*
Y008196*
X0643348*
Y0082015*
Y0082069*
X0643294*
Y0082123*
Y0082177*
X064324*
Y0082231*
X0643186*
Y0082285*
Y0082339*
X0643132*
Y0082393*
Y0082447*
X0643078*
Y0082501*
X0643024*
Y0082555*
Y0082609*
X064297*
Y0082663*
Y0082717*
X0642916*
Y0082771*
X0642862*
Y0082825*
Y008288*
X0642808*
Y0082934*
Y0082988*
X0642754*
Y0083042*
X06427*
Y0083096*
Y008315*
X0642646*
Y0083204*
Y0083258*
X0642591*
Y0083312*
Y0083366*
X0642537*
Y008342*
X0642483*
Y0083474*
Y0083528*
X0642429*
Y0083582*
Y0083636*
X0642375*
Y0083691*
X0642321*
Y0083745*
Y0083799*
X0642375*
Y0083853*
X0642429*
Y0083907*
X0642483*
Y0083961*
X0642537*
Y0084015*
X0642591*
Y0084069*
X0642646*
Y0084123*
X06427*
Y0084177*
X0642754*
Y0084231*
X0642808*
Y0084285*
X0642862*
Y0084339*
X0642916*
Y0084393*
X064297*
Y0084447*
X0643024*
Y0084501*
X0643078*
Y0084556*
X0643132*
Y008461*
X0643186*
Y0084664*
X064324*
Y0084718*
X0643294*
Y0084772*
X0643348*
Y0084826*
X0643402*
Y008488*
X0643457*
Y0084934*
X0643511*
Y0084988*
X0643565*
Y0085042*
Y0085096*
X0643619*
Y008515*
X0643673*
Y0085204*
X0643727*
Y0085258*
X0643781*
Y0085312*
X0643835*
Y0085366*
X0643889*
Y0085421*
Y0085474*
X0643943*
Y0085529*
Y0085583*
X0643997*
Y0085637*
Y0085691*
Y0085745*
Y0085799*
Y0085853*
Y0085907*
Y0085961*
Y0086015*
Y0086069*
Y0086123*
Y0086177*
Y0086231*
Y0086286*
Y0086339*
Y0086394*
Y0086448*
Y0086502*
Y0086556*
Y008661*
Y0086664*
Y0086718*
Y0086772*
Y0086826*
Y008688*
Y0086934*
Y0086988*
Y0087042*
Y0087096*
Y0087151*
Y0087204*
Y0087259*
Y0087313*
Y0087367*
Y0087421*
Y0087475*
Y0087529*
Y0087583*
Y0087637*
Y0087691*
Y0087745*
Y0087799*
Y0087853*
Y0087907*
Y0087961*
Y0088016*
Y0088069*
Y0088124*
Y0088178*
Y0088232*
Y0088286*
Y008834*
Y0088394*
Y0088448*
Y0088502*
Y0088556*
Y008861*
Y0088664*
Y0088718*
Y0088772*
Y0088826*
Y008888*
Y0088934*
Y0088989*
Y0089043*
Y0089097*
Y0089151*
Y0089205*
Y0089259*
Y0089313*
Y0089367*
Y0089421*
Y0089475*
Y0089529*
Y0089583*
Y0089637*
Y0089691*
Y0089745*
Y0089799*
Y0089854*
X0643943*
Y0089908*
Y0089962*
Y0090016*
X0643889*
Y009007*
Y0090124*
X0643835*
Y0090178*
X0643781*
Y0090232*
X0643727*
Y0090286*
X0643673*
Y009034*
X0643619*
Y0090394*
X0643565*
Y0090448*
X0643511*
Y0090502*
X0643457*
Y0090556*
X0643402*
Y009061*
X0643348*
Y0090664*
X0643294*
Y0090719*
X064324*
Y0090773*
X0643186*
Y0090827*
X0643132*
Y0090881*
X0643078*
Y0090935*
X0643024*
Y0090989*
X064297*
Y0091043*
X0642916*
Y0091097*
X0642862*
Y0091151*
X0642808*
Y0091205*
X0642754*
Y0091259*
X06427*
Y0091313*
X0642646*
Y0091367*
X0642591*
Y0091421*
X0642537*
Y0091475*
X0642483*
Y009153*
X0642429*
Y0091584*
X0642375*
Y0091638*
X0642267*
Y0091692*
X0642105*
Y0091746*
X0641835*
Y00918*
G37*
G36*
X0607776Y0091746D02*
X0607127D01*
Y0091692*
Y0091638*
Y0091584*
Y009153*
Y0091475*
Y0091421*
Y0091367*
Y0091313*
Y0091259*
Y0091205*
Y0091151*
X0607181*
Y0091097*
Y0091043*
Y0090989*
Y0090935*
Y0090881*
Y0090827*
Y0090773*
Y0090719*
Y0090664*
Y009061*
Y0090556*
X0607235*
Y0090502*
X0607181*
Y0090448*
X0607235*
Y0090394*
Y009034*
Y0090286*
Y0090232*
Y0090178*
Y0090124*
Y009007*
Y0090016*
Y0089962*
Y0089908*
X0607289*
Y0089854*
Y0089799*
Y0089745*
Y0089691*
Y0089637*
Y0089583*
Y0089529*
Y0089475*
X0607343*
Y0089421*
Y0089367*
Y0089313*
Y0089259*
Y0089205*
Y0089151*
Y0089097*
X0607397*
Y0089043*
Y0088989*
Y0088934*
Y008888*
Y0088826*
Y0088772*
X0607451*
Y0088718*
Y0088664*
Y008861*
Y0088556*
Y0088502*
X0607505*
Y0088448*
Y0088394*
Y008834*
Y0088286*
Y0088232*
X0607559*
Y0088178*
Y0088124*
Y0088069*
Y0088016*
Y0087961*
X0607613*
Y0087907*
Y0087853*
Y0087799*
Y0087745*
Y0087691*
X0607667*
Y0087637*
Y0087583*
Y0087529*
Y0087475*
X0607722*
Y0087421*
Y0087367*
Y0087313*
Y0087259*
X0607776*
Y0087204*
Y0087151*
Y0087096*
Y0087042*
X060783*
Y0086988*
Y0086934*
Y008688*
Y0086826*
X0607884*
Y0086772*
Y0086718*
Y0086664*
X0607938*
Y008661*
Y0086556*
Y0086502*
Y0086448*
X0607992*
Y0086394*
Y0086339*
Y0086286*
X0608046*
Y0086231*
Y0086177*
Y0086123*
X06081*
Y0086069*
Y0086015*
Y0085961*
X0608154*
Y0085907*
Y0085853*
Y0085799*
X0608208*
Y0085745*
Y0085691*
Y0085637*
X0608262*
Y0085583*
Y0085529*
Y0085474*
X0608316*
Y0085421*
Y0085366*
Y0085312*
X060837*
Y0085258*
Y0085204*
Y008515*
X0608424*
Y0085096*
Y0085042*
Y0084988*
X0608478*
Y0084934*
Y008488*
X0608532*
Y0084826*
Y0084772*
Y0084718*
X0608587*
Y0084664*
Y008461*
X0608641*
Y0084556*
Y0084501*
Y0084447*
X0608695*
Y0084393*
Y0084339*
X0608749*
Y0084285*
Y0084231*
Y0084177*
X0608803*
Y0084123*
Y0084069*
X0608857*
Y0084015*
Y0083961*
X0608911*
Y0083907*
Y0083853*
Y0083799*
X0608965*
Y0083745*
Y0083691*
X0609019*
Y0083636*
Y0083582*
X0609073*
Y0083528*
Y0083474*
X0609127*
Y008342*
Y0083366*
X0609181*
Y0083312*
Y0083258*
X0609235*
Y0083204*
Y008315*
X0609289*
Y0083096*
Y0083042*
X0609343*
Y0082988*
Y0082934*
X0609397*
Y008288*
Y0082825*
X0609451*
Y0082771*
Y0082717*
X0609506*
Y0082663*
Y0082609*
X060956*
Y0082555*
Y0082501*
X0609614*
Y0082447*
Y0082393*
X0609668*
Y0082339*
X0609722*
Y0082285*
Y0082231*
X0609776*
Y0082177*
Y0082123*
X060983*
Y0082069*
Y0082015*
X0609884*
Y008196*
Y0081906*
X0609938*
Y0081852*
X0609992*
Y0081798*
Y0081744*
X0610046*
Y008169*
Y0081636*
X06101*
Y0081582*
Y0081528*
X0610154*
Y0081474*
X0610208*
Y008142*
Y0081366*
X0610262*
Y0081312*
X0610317*
Y0081258*
Y0081204*
X0610371*
Y008115*
Y0081095*
X0610425*
Y0081042*
X0610479*
Y0080987*
Y0080933*
X0610533*
Y0080879*
X0610587*
Y0080825*
Y0080771*
X0610641*
Y0080717*
X0610695*
Y0080663*
Y0080609*
X0610749*
Y0080555*
X0610803*
Y0080501*
Y0080447*
X0610857*
Y0080393*
X0610911*
Y0080339*
X0610965*
Y0080285*
Y008023*
X0611019*
Y0080177*
X0611073*
Y0080122*
Y0080068*
X0611127*
Y0080014*
X0611181*
Y007996*
X0611236*
Y0079906*
Y0079852*
X061129*
Y0079798*
X0611344*
Y0079744*
X0611398*
Y007969*
Y0079636*
X0611452*
Y0079582*
X0611506*
Y0079528*
X061156*
Y0079474*
X0611614*
Y007942*
Y0079365*
X0611668*
Y0079312*
X0611722*
Y0079257*
X0611776*
Y0079203*
X061183*
Y0079149*
Y0079095*
X0611884*
Y0079041*
X0611938*
Y0078987*
X0611992*
Y0078933*
X0612046*
Y0078879*
Y0078825*
X0612101*
Y0078771*
X0612155*
Y0078717*
X0612209*
Y0078663*
X0612263*
Y0078609*
X0612317*
Y0078555*
X0612371*
Y00785*
X0612425*
Y0078447*
Y0078392*
X0612479*
Y0078338*
X0612533*
Y0078284*
X0612587*
Y007823*
X0612641*
Y0078176*
X0612695*
Y0078122*
X0612749*
Y0078068*
X0612803*
Y0078014*
X0612857*
Y007796*
X0612912*
Y0077906*
X0612965*
Y0077852*
X061302*
Y0077798*
X0613074*
Y0077744*
X0613128*
Y007769*
X0613182*
Y0077636*
X0613236*
Y0077582*
X061329*
Y0077527*
X0613344*
Y0077473*
X0613398*
Y0077419*
X0613452*
Y0077365*
X0613506*
Y0077311*
X061356*
Y0077257*
X0613614*
Y0077203*
X0613668*
Y0077149*
X0613722*
Y0077095*
X0613776*
Y0077041*
X0613831*
Y0076987*
X0613885*
Y0076933*
X0613939*
Y0076879*
X0613993*
Y0076825*
X0614047*
Y0076771*
X0614155*
Y0076717*
X0614209*
Y0076662*
X0614263*
Y0076608*
X0614317*
Y0076554*
X0614371*
Y00765*
X0614425*
Y0076446*
X0614479*
Y0076392*
X0614587*
Y0076338*
X0614641*
Y0076284*
X0614696*
Y007623*
X061475*
Y0076176*
X0614804*
Y0076122*
X0614912*
Y0076068*
X0614966*
Y0076014*
X061502*
Y007596*
X0615074*
Y0075906*
X0615182*
Y0075852*
X0615236*
Y0075797*
X061529*
Y0075743*
X0615398*
Y0075689*
X0615452*
Y0075635*
X0615507*
Y0075581*
X0615615*
Y0075527*
X0615669*
Y0075473*
X0615723*
Y0075419*
X0615831*
Y0075365*
X0615885*
Y0075311*
X0615993*
Y0075257*
X0616047*
Y0075203*
X0616101*
Y0075149*
X0616209*
Y0075095*
X0616263*
Y0075041*
X0616371*
Y0074986*
X0616426*
Y0074932*
X0616534*
Y0074878*
X0616588*
Y0074824*
X0616696*
Y007477*
X061675*
Y0074716*
X0616858*
Y0074662*
X0616966*
Y0074608*
X061702*
Y0074554*
X0617128*
Y00745*
X0617182*
Y0074446*
X061729*
Y0074392*
X0617399*
Y0074338*
X0617453*
Y0074284*
X0617561*
Y007423*
X0617669*
Y0074176*
X0617777*
Y0074121*
X0617831*
Y0074067*
X0617939*
Y0074013*
X0618047*
Y0073959*
X0618155*
Y0073905*
X0618264*
Y0073851*
X0618372*
Y0073797*
X061848*
Y0073743*
X0618588*
Y0073689*
X0618696*
Y0073635*
X0618804*
Y0073581*
X0618912*
Y0073527*
X0619021*
Y0073473*
X0619129*
Y0073419*
X0619237*
Y0073365*
X0619345*
Y0073311*
X0619453*
Y0073256*
X0619615*
Y0073203*
X0619723*
Y0073148*
X0619831*
Y0073094*
X0619994*
Y007304*
X0620102*
Y0072986*
X0620264*
Y0072932*
X0620372*
Y0072878*
X0620534*
Y0072824*
X0620642*
Y007277*
X0620805*
Y0072716*
X0620967*
Y0072662*
X0621129*
Y0072608*
X0621237*
Y0072554*
X0621399*
Y00725*
X0621561*
Y0072446*
X0621778*
Y0072391*
X062194*
Y0072338*
X0622102*
Y0072283*
X0622318*
Y0072229*
X062248*
Y0072175*
X0622697*
Y0072121*
X0622913*
Y0072067*
X0623129*
Y0072013*
X0623345*
Y0071959*
X0623616*
Y0071905*
X0623832*
Y0071851*
X0624102*
Y0071797*
X0624427*
Y0071743*
X0624751*
Y0071689*
X062513*
Y0071635*
X0625508*
Y0071581*
X0626049*
Y0071526*
X0626697*
Y0071473*
X0629292*
Y0071526*
X0629995*
Y0071581*
X0630482*
Y0071635*
X0630914*
Y0071689*
X0631293*
Y0071743*
X0631617*
Y0071797*
X0631887*
Y0071851*
X0632212*
Y0071905*
X0632428*
Y0071959*
X0632644*
Y0072013*
X0632914*
Y0072067*
X0633131*
Y0072121*
X0633347*
Y0072175*
X0633563*
Y0072229*
X0633725*
Y0072283*
X0633942*
Y0072338*
X0634104*
Y0072391*
X0634266*
Y0072446*
X0634428*
Y00725*
X063459*
Y0072554*
X0634753*
Y0072608*
X0634915*
Y0072662*
X0635077*
Y0072716*
X0635239*
Y007277*
X0635401*
Y0072824*
X0635509*
Y0072878*
X0635672*
Y0072932*
X063578*
Y0072986*
X0635942*
Y007304*
X063605*
Y0073094*
X0636212*
Y0073148*
X063632*
Y0073203*
X0636428*
Y0073256*
X0636591*
Y0073311*
X0636699*
Y0073365*
X0636807*
Y0073419*
X0636915*
Y0073473*
X0637023*
Y0073527*
X0637131*
Y0073581*
X0637239*
Y0073635*
X0637348*
Y0073689*
X0637456*
Y0073743*
X0637564*
Y0073797*
X0637672*
Y0073851*
X063778*
Y0073905*
X0637888*
Y0073959*
X0637996*
Y0074013*
X0638104*
Y0074067*
X0638158*
Y0074121*
X0638267*
Y0074176*
X0638375*
Y007423*
X0638483*
Y0074284*
X0638537*
Y0074338*
X0638645*
Y0074392*
X0638753*
Y0074446*
X0638807*
Y00745*
X0638915*
Y0074554*
X0639023*
Y0074608*
X0639078*
Y0074662*
X0639186*
Y0074716*
X063924*
Y007477*
X0639348*
Y0074824*
X0639456*
Y0074878*
X063951*
Y0074932*
X0639618*
Y0074986*
X0639672*
Y0075041*
X063978*
Y0075095*
X0639834*
Y0075149*
X0639888*
Y0075203*
X0639996*
Y0075257*
X0640051*
Y0075311*
X0640159*
Y0075365*
X0640213*
Y0075419*
X0640321*
Y0075473*
X0640375*
Y0075527*
X0640429*
Y0075581*
X0640537*
Y0075635*
X0640591*
Y0075689*
X0640645*
Y0075743*
X0640753*
Y0075797*
X0640807*
Y0075852*
X0640862*
Y0075906*
X0640916*
Y007596*
X0641024*
Y0076014*
X0641078*
Y0076068*
X0641132*
Y0076122*
X0641186*
Y0076176*
X0641294*
Y007623*
X0641348*
Y0076284*
X0641402*
Y0076338*
X0641456*
Y0076392*
X064151*
Y0076446*
X0641618*
Y00765*
X0641673*
Y0076554*
X0641726*
Y0076608*
X0641781*
Y0076662*
X0641835*
Y0076717*
X0641889*
Y0076771*
X0641943*
Y0076825*
X0642051*
Y0076879*
X0642105*
Y0076933*
X0642159*
Y0076987*
X0642213*
Y0077041*
X0642267*
Y0077095*
X0642321*
Y0077149*
X0642375*
Y0077203*
X0642429*
Y0077257*
X0642483*
Y0077311*
X0642537*
Y0077365*
X0642591*
Y0077419*
X0642646*
Y0077473*
X06427*
Y0077527*
X0642754*
Y0077582*
X0642808*
Y0077636*
X0642862*
Y007769*
X0642916*
Y0077744*
X064297*
Y0077798*
X0643024*
Y0077852*
X0643078*
Y0077906*
X0643132*
Y007796*
X0643186*
Y0078014*
X064324*
Y0078068*
X0643294*
Y0078122*
X0643348*
Y0078176*
X0643402*
Y007823*
X0643457*
Y0078284*
X0643511*
Y0078338*
X0643565*
Y0078392*
Y0078447*
X0643619*
Y00785*
X0643673*
Y0078555*
X0643727*
Y0078609*
X0643781*
Y0078663*
X0643835*
Y0078717*
X0643889*
Y0078771*
X0643943*
Y0078825*
Y0078879*
X0643997*
Y0078933*
X0643132*
Y0078879*
X0643078*
Y0078825*
X0643024*
Y0078771*
Y0078717*
X064297*
Y0078663*
X0642916*
Y0078609*
X0642862*
Y0078555*
X0642808*
Y00785*
X0642754*
Y0078447*
X06427*
Y0078392*
X0642646*
Y0078338*
X0642591*
Y0078284*
X0642537*
Y007823*
X0642483*
Y0078176*
X0642429*
Y0078122*
X0642375*
Y0078068*
X0642321*
Y0078014*
X0642267*
Y007796*
X0642213*
Y0077906*
X0642159*
Y0077852*
X0642105*
Y0077798*
X0642051*
Y0077744*
X0641997*
Y007769*
X0641943*
Y0077636*
X0641889*
Y0077582*
X0641835*
Y0077527*
X0641781*
Y0077473*
X0641726*
Y0077419*
X0641673*
Y0077365*
X0641564*
Y0077311*
X064151*
Y0077257*
X0641456*
Y0077203*
X0641402*
Y0077149*
X0641348*
Y0077095*
X0641294*
Y0077041*
X064124*
Y0076987*
X0641132*
Y0076933*
X0641078*
Y0076879*
X0641024*
Y0076825*
X064097*
Y0076771*
X0640916*
Y0076717*
X0640807*
Y0076662*
X0640753*
Y0076608*
X0640699*
Y0076554*
X0640645*
Y00765*
X0640537*
Y0076446*
X0640483*
Y0076392*
X0640429*
Y0076338*
X0640375*
Y0076284*
X0640267*
Y007623*
X0640213*
Y0076176*
X0640159*
Y0076122*
X0640051*
Y0076068*
X0639996*
Y0076014*
X0639943*
Y007596*
X0639834*
Y0075906*
X063978*
Y0075852*
X0639672*
Y0075797*
X0639618*
Y0075743*
X0639564*
Y0075689*
X0639456*
Y0075635*
X0639402*
Y0075581*
X0639294*
Y0075527*
X063924*
Y0075473*
X0639131*
Y0075419*
X0639078*
Y0075365*
X0638969*
Y0075311*
X0638915*
Y0075257*
X0638807*
Y0075203*
X0638699*
Y0075149*
X0638645*
Y0075095*
X0638537*
Y0075041*
X0638429*
Y0074986*
X0638375*
Y0074932*
X0638267*
Y0074878*
X0638158*
Y0074824*
X0638104*
Y007477*
X0637996*
Y0074716*
X0637888*
Y0074662*
X063778*
Y0074608*
X0637726*
Y0074554*
X0637618*
Y00745*
X063751*
Y0074446*
X0637402*
Y0074392*
X0637293*
Y0074338*
X0637185*
Y0074284*
X0637077*
Y007423*
X0636969*
Y0074176*
X0636861*
Y0074121*
X0636753*
Y0074067*
X0636645*
Y0074013*
X0636537*
Y0073959*
X0636428*
Y0073905*
X063632*
Y0073851*
X0636158*
Y0073797*
X063605*
Y0073743*
X0635888*
Y0073689*
X063578*
Y0073635*
X0635672*
Y0073581*
X0635509*
Y0073527*
X0635401*
Y0073473*
X0635239*
Y0073419*
X0635077*
Y0073365*
X0634969*
Y0073311*
X0634807*
Y0073256*
X0634644*
Y0073203*
X0634482*
Y0073148*
X063432*
Y0073094*
X0634158*
Y007304*
X0633996*
Y0072986*
X0633834*
Y0072932*
X0633617*
Y0072878*
X0633455*
Y0072824*
X0633239*
Y007277*
X0633022*
Y0072716*
X0632806*
Y0072662*
X063259*
Y0072608*
X063232*
Y0072554*
X0632103*
Y00725*
X0631833*
Y0072446*
X0631509*
Y0072391*
X0631184*
Y0072338*
X0630806*
Y0072283*
X0630482*
Y0072229*
X0629833*
Y0072175*
X0629238*
Y0072121*
X0629184*
Y0072175*
X0629076*
Y0072121*
X0626968*
Y0072175*
X0626157*
Y0072229*
X062567*
Y0072283*
X0625238*
Y0072338*
X0624859*
Y0072391*
X0624535*
Y0072446*
X062421*
Y00725*
X062394*
Y0072554*
X062367*
Y0072608*
X0623454*
Y0072662*
X0623237*
Y0072716*
X0623021*
Y007277*
X0622805*
Y0072824*
X0622589*
Y0072878*
X0622426*
Y0072932*
X062221*
Y0072986*
X0622048*
Y007304*
X0621886*
Y0073094*
X0621724*
Y0073148*
X0621561*
Y0073203*
X0621399*
Y0073256*
X0621237*
Y0073311*
X0621075*
Y0073365*
X0620913*
Y0073419*
X0620805*
Y0073473*
X0620642*
Y0073527*
X0620534*
Y0073581*
X0620372*
Y0073635*
X0620264*
Y0073689*
X0620102*
Y0073743*
X0619994*
Y0073797*
X0619885*
Y0073851*
X0619777*
Y0073905*
X0619615*
Y0073959*
X0619507*
Y0074013*
X0619399*
Y0074067*
X0619291*
Y0074121*
X0619183*
Y0074176*
X0619074*
Y007423*
X0618966*
Y0074284*
X0618858*
Y0074338*
X061875*
Y0074392*
X0618642*
Y0074446*
X0618534*
Y00745*
X0618426*
Y0074554*
X0618318*
Y0074608*
X0618264*
Y0074662*
X0618155*
Y0074716*
X0618047*
Y007477*
X0617939*
Y0074824*
X0617831*
Y0074878*
X0617777*
Y0074932*
X0617669*
Y0074986*
X0617561*
Y0075041*
X0617507*
Y0075095*
X0617399*
Y0075149*
X0617345*
Y0075203*
X0617236*
Y0075257*
X0617128*
Y0075311*
X0617074*
Y0075365*
X0616966*
Y0075419*
X0616912*
Y0075473*
X0616804*
Y0075527*
X061675*
Y0075581*
X0616642*
Y0075635*
X0616588*
Y0075689*
X061648*
Y0075743*
X0616426*
Y0075797*
X0616317*
Y0075852*
X0616263*
Y0075906*
X0616209*
Y007596*
X0616101*
Y0076014*
X0616047*
Y0076068*
X0615993*
Y0076122*
X0615885*
Y0076176*
X0615831*
Y007623*
X0615777*
Y0076284*
X0615669*
Y0076338*
X0615615*
Y0076392*
X061556*
Y0076446*
X0615452*
Y00765*
X0615398*
Y0076554*
X0615344*
Y0076608*
X061529*
Y0076662*
X0615182*
Y0076717*
X0615128*
Y0076771*
X0615074*
Y0076825*
X061502*
Y0076879*
X0614966*
Y0076933*
X0614858*
Y0076987*
X0614804*
Y0077041*
X061475*
Y0077095*
X0614696*
Y0077149*
X0614641*
Y0077203*
X0614587*
Y0077257*
X0614533*
Y0077311*
X0614425*
Y0077365*
X0614371*
Y0077419*
X0614317*
Y0077473*
X0614263*
Y0077527*
X0614209*
Y0077582*
X0614155*
Y0077636*
X0614101*
Y007769*
X0614047*
Y0077744*
X0613993*
Y0077798*
X0613939*
Y0077852*
X0613885*
Y0077906*
X0613831*
Y007796*
X0613776*
Y0078014*
X0613722*
Y0078068*
X0613668*
Y0078122*
X0613614*
Y0078176*
X061356*
Y007823*
X0613506*
Y0078284*
X0613452*
Y0078338*
X0613398*
Y0078392*
X0613344*
Y0078447*
X061329*
Y00785*
X0613236*
Y0078555*
X0613182*
Y0078609*
X0613128*
Y0078663*
X0613074*
Y0078717*
X061302*
Y0078771*
X0612965*
Y0078825*
Y0078879*
X0612912*
Y0078933*
X0612857*
Y0078987*
X0612803*
Y0079041*
X0612749*
Y0079095*
X0612695*
Y0079149*
X0612641*
Y0079203*
X0612587*
Y0079257*
Y0079312*
X0612533*
Y0079365*
X0612479*
Y007942*
X0612425*
Y0079474*
X0612371*
Y0079528*
X0612317*
Y0079582*
Y0079636*
X0612263*
Y007969*
X0612209*
Y0079744*
X0612155*
Y0079798*
X0612101*
Y0079852*
Y0079906*
X0612046*
Y007996*
X0611992*
Y0080014*
X0611938*
Y0080068*
Y0080122*
X0611884*
Y0080177*
X061183*
Y008023*
X0611776*
Y0080285*
Y0080339*
X0611722*
Y0080393*
X0611668*
Y0080447*
X0611614*
Y0080501*
Y0080555*
X061156*
Y0080609*
X0611506*
Y0080663*
X0611452*
Y0080717*
Y0080771*
X0611398*
Y0080825*
X0611344*
Y0080879*
Y0080933*
X061129*
Y0080987*
X0611236*
Y0081042*
Y0081095*
X0611181*
Y008115*
X0611127*
Y0081204*
Y0081258*
X0611073*
Y0081312*
X0611019*
Y0081366*
Y008142*
X0610965*
Y0081474*
X0610911*
Y0081528*
Y0081582*
X0610857*
Y0081636*
Y008169*
X0610803*
Y0081744*
X0610749*
Y0081798*
Y0081852*
X0610695*
Y0081906*
X0610641*
Y008196*
Y0082015*
X0610587*
Y0082069*
Y0082123*
X0610533*
Y0082177*
Y0082231*
X0610479*
Y0082285*
X0610425*
Y0082339*
Y0082393*
X0610371*
Y0082447*
Y0082501*
X0610317*
Y0082555*
Y0082609*
X0610262*
Y0082663*
X0610208*
Y0082717*
Y0082771*
X0610154*
Y0082825*
Y008288*
X06101*
Y0082934*
Y0082988*
X0610046*
Y0083042*
Y0083096*
X0609992*
Y008315*
Y0083204*
X0609938*
Y0083258*
Y0083312*
X0609884*
Y0083366*
Y008342*
X060983*
Y0083474*
Y0083528*
X0609776*
Y0083582*
Y0083636*
X0609722*
Y0083691*
Y0083745*
X0609668*
Y0083799*
Y0083853*
X0609614*
Y0083907*
Y0083961*
X060956*
Y0084015*
Y0084069*
Y0084123*
X0609506*
Y0084177*
Y0084231*
X0609451*
Y0084285*
Y0084339*
X0609397*
Y0084393*
Y0084447*
Y0084501*
X0609343*
Y0084556*
Y008461*
X0609289*
Y0084664*
Y0084718*
X0609235*
Y0084772*
Y0084826*
Y008488*
X0609181*
Y0084934*
Y0084988*
X0609127*
Y0085042*
Y0085096*
Y008515*
X0609073*
Y0085204*
Y0085258*
Y0085312*
X0609019*
Y0085366*
Y0085421*
X0608965*
Y0085474*
Y0085529*
Y0085583*
X0608911*
Y0085637*
Y0085691*
Y0085745*
X0608857*
Y0085799*
Y0085853*
Y0085907*
X0608803*
Y0085961*
Y0086015*
Y0086069*
X0608749*
Y0086123*
Y0086177*
Y0086231*
X0608695*
Y0086286*
Y0086339*
Y0086394*
X0608641*
Y0086448*
Y0086502*
Y0086556*
X0608587*
Y008661*
Y0086664*
Y0086718*
Y0086772*
X0608532*
Y0086826*
Y008688*
Y0086934*
X0608478*
Y0086988*
Y0087042*
Y0087096*
Y0087151*
X0608424*
Y0087204*
Y0087259*
Y0087313*
Y0087367*
X060837*
Y0087421*
Y0087475*
Y0087529*
Y0087583*
X0608316*
Y0087637*
Y0087691*
Y0087745*
Y0087799*
X0608262*
Y0087853*
Y0087907*
Y0087961*
Y0088016*
Y0088069*
X0608208*
Y0088124*
Y0088178*
Y0088232*
Y0088286*
Y008834*
X0608154*
Y0088394*
Y0088448*
Y0088502*
Y0088556*
Y008861*
X06081*
Y0088664*
Y0088718*
Y0088772*
Y0088826*
Y008888*
X0608046*
Y0088934*
Y0088989*
Y0089043*
Y0089097*
Y0089151*
Y0089205*
X0607992*
Y0089259*
Y0089313*
Y0089367*
Y0089421*
Y0089475*
Y0089529*
Y0089583*
X0607938*
Y0089637*
Y0089691*
Y0089745*
Y0089799*
Y0089854*
Y0089908*
Y0089962*
Y0090016*
X0607884*
Y009007*
Y0090124*
Y0090178*
Y0090232*
Y0090286*
Y009034*
Y0090394*
Y0090448*
Y0090502*
Y0090556*
X060783*
Y009061*
Y0090664*
Y0090719*
Y0090773*
Y0090827*
Y0090881*
Y0090935*
Y0090989*
Y0091043*
Y0091097*
Y0091151*
Y0091205*
Y0091259*
Y0091313*
Y0091367*
Y0091421*
X0607776*
Y0091475*
Y009153*
Y0091584*
Y0091638*
Y0091692*
Y0091746*
G37*
%LNtimecard-dc-beta-v1-3*%
%LPD*%
G36*
X0652431Y008888D02*
X0652539D01*
Y0088826*
Y0088772*
Y0088718*
Y0088664*
Y008861*
Y0088556*
Y0088502*
Y0088448*
Y0088394*
Y008834*
Y0088286*
Y0088232*
Y0088178*
Y0088124*
Y0088069*
Y0088016*
Y0087961*
Y0087907*
Y0087853*
Y0087799*
Y0087745*
Y0087691*
Y0087637*
Y0087583*
Y0087529*
Y0087475*
Y0087421*
Y0087367*
Y0087313*
Y0087259*
Y0087204*
Y0087151*
Y0087096*
Y0087042*
Y0086988*
Y0086934*
Y008688*
Y0086826*
Y0086772*
Y0086718*
Y0086664*
Y008661*
Y0086556*
Y0086502*
Y0086448*
Y0086394*
Y0086339*
Y0086286*
Y0086231*
Y0086177*
Y0086123*
Y0086069*
Y0086015*
Y0085961*
Y0085907*
Y0085853*
Y0085799*
Y0085745*
Y0085691*
Y0085637*
Y0085583*
Y0085529*
Y0085474*
Y0085421*
Y0085366*
Y0085312*
Y0085258*
Y0085204*
Y008515*
Y0085096*
Y0085042*
Y0084988*
Y0084934*
Y008488*
Y0084826*
Y0084772*
Y0084718*
Y0084664*
Y008461*
Y0084556*
Y0084501*
Y0084447*
Y0084393*
Y0084339*
Y0084285*
Y0084231*
Y0084177*
Y0084123*
Y0084069*
Y0084015*
Y0083961*
Y0083907*
Y0083853*
Y0083799*
Y0083745*
Y0083691*
Y0083636*
Y0083582*
Y0083528*
Y0083474*
Y008342*
Y0083366*
Y0083312*
Y0083258*
Y0083204*
Y008315*
Y0083096*
Y0083042*
Y0082988*
Y0082934*
Y008288*
X0648592*
Y0082934*
Y0082988*
Y0083042*
Y0083096*
Y008315*
Y0083204*
Y0083258*
Y0083312*
Y0083366*
Y008342*
Y0083474*
Y0083528*
Y0083582*
Y0083636*
Y0083691*
Y0083745*
Y0083799*
Y0083853*
Y0083907*
Y0083961*
Y0084015*
Y0084069*
Y0084123*
Y0084177*
Y0084231*
Y0084285*
Y0084339*
Y0084393*
Y0084447*
Y0084501*
Y0084556*
Y008461*
Y0084664*
Y0084718*
Y0084772*
Y0084826*
Y008488*
Y0084934*
Y0084988*
Y0085042*
Y0085096*
Y008515*
Y0085204*
Y0085258*
Y0085312*
Y0085366*
Y0085421*
Y0085474*
Y0085529*
Y0085583*
Y0085637*
Y0085691*
Y0085745*
Y0085799*
Y0085853*
Y0085907*
Y0085961*
Y0086015*
Y0086069*
Y0086123*
Y0086177*
Y0086231*
Y0086286*
Y0086339*
Y0086394*
Y0086448*
Y0086502*
Y0086556*
Y008661*
Y0086664*
Y0086718*
Y0086772*
Y0086826*
Y008688*
Y0086934*
Y0086988*
Y0087042*
Y0087096*
Y0087151*
Y0087204*
Y0087259*
Y0087313*
Y0087367*
Y0087421*
Y0087475*
Y0087529*
Y0087583*
Y0087637*
Y0087691*
Y0087745*
Y0087799*
Y0087853*
Y0087907*
Y0087961*
Y0088016*
Y0088069*
Y0088124*
Y0088178*
Y0088232*
Y0088286*
Y008834*
Y0088394*
Y0088448*
Y0088502*
Y0088556*
Y008861*
Y0088664*
Y0088718*
Y0088772*
Y0088826*
Y008888*
X0648646*
Y0088934*
X0648701*
Y008888*
X0652214*
Y0088934*
X0652269*
Y008888*
X0652377*
Y0088934*
X0652431*
Y008888*
G37*
G36*
X0641024Y0088989D02*
Y0088934D01*
Y008888*
Y0088826*
Y0088772*
Y0088718*
Y0088664*
Y008861*
Y0088556*
Y0088502*
Y0088448*
Y0088394*
Y008834*
Y0088286*
Y0088232*
Y0088178*
Y0088124*
Y0088069*
Y0088016*
Y0087961*
Y0087907*
Y0087853*
Y0087799*
Y0087745*
Y0087691*
Y0087637*
Y0087583*
Y0087529*
Y0087475*
Y0087421*
Y0087367*
Y0087313*
Y0087259*
Y0087204*
Y0087151*
Y0087096*
Y0087042*
Y0086988*
Y0086934*
Y008688*
Y0086826*
Y0086772*
Y0086718*
Y0086664*
Y008661*
Y0086556*
Y0086502*
Y0086448*
Y0086394*
Y0086339*
Y0086286*
Y0086231*
Y0086177*
X0636969*
Y0086231*
Y0086286*
Y0086339*
Y0086394*
Y0086448*
Y0086502*
Y0086556*
Y008661*
Y0086664*
Y0086718*
Y0086772*
Y0086826*
Y008688*
Y0086934*
Y0086988*
Y0087042*
Y0087096*
Y0087151*
Y0087204*
Y0087259*
Y0087313*
Y0087367*
Y0087421*
Y0087475*
Y0087529*
Y0087583*
Y0087637*
Y0087691*
Y0087745*
Y0087799*
Y0087853*
Y0087907*
Y0087961*
Y0088016*
Y0088069*
Y0088124*
Y0088178*
Y0088232*
Y0088286*
Y008834*
Y0088394*
Y0088448*
Y0088502*
Y0088556*
Y008861*
Y0088664*
Y0088718*
Y0088772*
Y0088826*
Y008888*
Y0088934*
Y0088989*
Y0089043*
X0641024*
Y0088989*
G37*
G54D22*
X0106693Y0161417D03*
X0112205D03*
X0631496Y0274016D03*
X0637008D03*
X0631496Y0253543D03*
X0637008D03*
X0631496Y026063D03*
X0637008D03*
X0631496Y0267323D03*
X0637008D03*
X066874Y0161106D03*
X0663228D03*
X066874Y0167106D03*
X0663228D03*
X066874Y0172106D03*
X0663228D03*
X066874Y0177606D03*
X0663228D03*
X0684728Y0209606D03*
X069024D03*
X061524Y0217106D03*
X0609728D03*
X0361516Y0064567D03*
X0356004D03*
X0519882Y0292323D03*
X0525394D03*
X010748Y0237205D03*
X0112992D03*
X010748Y0184055D03*
X0112992D03*
X0111811Y0110433D03*
X0106299D03*
X0356299Y0295276D03*
X0350787D03*
X0324803Y0269685D03*
X0319291D03*
G54D23*
X0113976Y0152362D03*
Y0144882D03*
X0104528D03*
Y0148622D03*
Y0152362D03*
X0104331Y0100394D03*
Y0096653D03*
Y0092913D03*
X0113779D03*
Y0100394D03*
X0114961Y024626D03*
Y025D03*
Y025374D03*
X0105512D03*
Y024626D03*
X0114961Y019311D03*
Y019685D03*
Y0200591D03*
X0105512D03*
Y019311D03*
G54D24*
X0052165Y0112795D03*
X0052362Y0218701D03*
G54D25*
X0058858Y0112795D03*
Y0121457D03*
X0051378D03*
X0059055Y0218701D03*
Y0227362D03*
X0051575D03*
G54D26*
X0052559Y0084744D03*
Y0096358D03*
Y0189469D03*
Y0201083D03*
Y0242224D03*
Y0253839D03*
Y01375D03*
Y0149114D03*
G54D27*
X0058563Y0090551D03*
Y0195276D03*
Y0248031D03*
Y0143307D03*
G54D28*
X0213583Y0357677D03*
Y0362795D03*
X0204724Y0360236D03*
X0159941Y0357677D03*
Y0362795D03*
X0151083Y0360236D03*
X0177657Y0357677D03*
Y0362795D03*
X0168799Y0360236D03*
X0195866Y0357677D03*
Y0362795D03*
X0187008Y0360236D03*
G54D29*
X061574Y0224106D03*
Y0229106D03*
Y0234106D03*
Y0239106D03*
X0635228D03*
Y0234106D03*
Y0229106D03*
Y0224106D03*
X0683228Y0203106D03*
Y0198106D03*
Y0193106D03*
Y0188106D03*
X066374D03*
Y0193106D03*
Y0198106D03*
Y0203106D03*
G54D30*
X0185827Y0067421D03*
Y0053051D03*
G54D31*
X020161Y0422114D03*
Y0395106D03*
X019161Y0422114D03*
Y0395106D03*
X018161Y0422114D03*
Y0395106D03*
X017161Y0422114D03*
Y0395106D03*
X016161Y0422114D03*
Y0395106D03*
G54D32*
X0407805Y0176893D03*
X0392057D03*
X0407805Y0174893D03*
X0392057D03*
X0407805Y0172893D03*
X0392057D03*
X0407805Y0170893D03*
X0392057D03*
X0407805Y0168893D03*
X0392057D03*
X0407805Y0166893D03*
X0392057D03*
X0407805Y0164893D03*
X0392057D03*
X0407805Y0162893D03*
X0392057D03*
X0407805Y0160893D03*
X0392057D03*
Y0158893D03*
X0407805D03*
G54D33*
X0201772Y0378937D03*
Y0371063D03*
X0161417Y0378937D03*
Y0371063D03*
X017126Y0378937D03*
Y0371063D03*
X0181102Y0378937D03*
Y0371063D03*
G54D34*
X0455709Y0284941D03*
Y0289862D03*
X0064173Y0405217D03*
Y0410532D03*
X0084646Y0405217D03*
Y0410532D03*
X0104724Y0405217D03*
Y0410532D03*
X0124803Y0405217D03*
Y0410532D03*
G54D35*
X0237205Y0272638D03*
Y0278543D03*
X024311Y0272638D03*
Y0278543D03*
G54D36*
X0298524Y0269685D03*
X0293996D03*
G54D37*
X0097441Y025374D03*
Y0248228D03*
Y0142913D03*
Y0148425D03*
X049311Y027874D03*
Y0284252D03*
X0097441Y0196063D03*
Y0201575D03*
Y0090748D03*
Y009626D03*
G54D38*
X0523228Y0277559D03*
X051811D03*
X0523228Y0285433D03*
X051811D03*
G54D39*
X0612284Y024339D03*
Y0248823D03*
X0194488Y0067244D03*
Y0061811D03*
X0612992Y0280748D03*
Y0286181D03*
X0674984Y020889D03*
Y0214323D03*
X0623484Y021289D03*
Y0218323D03*
X07Y0187835D03*
Y0193268D03*
X0600394Y0233504D03*
Y0238937D03*
G54D40*
X0305512Y0057382D03*
Y0060728D03*
X0250394Y0057382D03*
Y0060728D03*
G54D41*
X0309646Y001378D03*
X0187599D03*
X0183661D03*
X0179725D03*
X0207283D03*
X025059D03*
X0293898D03*
X0289961D03*
X027815D03*
X0274213D03*
X0262402D03*
X0258465D03*
X0242717D03*
X0238779D03*
X0215158D03*
X0211221D03*
X0230906D03*
X0301771D03*
X0195473D03*
X0199409D03*
X0219094D03*
X0297834D03*
X0286023D03*
X0270275D03*
X0266338D03*
X0203346D03*
X0191535D03*
X0282086D03*
X0234842D03*
X0246654D03*
X0254527D03*
G54D42*
X0305709Y001573D03*
G54D43*
X0535433Y0290433D03*
Y0285433D03*
Y0280433D03*
Y0275433D03*
X0554331Y0290433D03*
Y0285433D03*
Y0280433D03*
Y0275433D03*
G54D44*
X0465158Y028998D03*
Y028498D03*
Y027998D03*
Y027498D03*
X0483661Y028998D03*
Y028498D03*
Y027998D03*
Y027498D03*
G54D45*
X0667984Y0242012D03*
Y0280201D03*
X0631984Y0146012D03*
Y0184201D03*
G54D46*
X0263779Y0362205D03*
Y0354331D03*
Y0346457D03*
Y0338583D03*
X024628Y0362205D03*
Y0346457D03*
Y0354331D03*
Y0338583D03*
G54D47*
X0221259Y0103817D03*
X029803Y0235868D03*
X0258661Y0251812D03*
X0248817D03*
X0238976D03*
X0229133D03*
X0288188Y0235868D03*
X0278345D03*
X0268502D03*
X0258661D03*
X0248817D03*
X0238976D03*
X0229133D03*
X0294093D03*
X0296061D03*
X0290157D03*
X0292125D03*
X028425D03*
X028622D03*
X0280313D03*
X0282282D03*
X0274409D03*
X0276377D03*
X0254724D03*
X0256692D03*
X0250786D03*
X0235038D03*
X0237006D03*
X0221258Y0251812D03*
X0223228D03*
Y0235868D03*
X0221258D03*
X0225196Y0251812D03*
X0227165D03*
X0240944D03*
X0242913D03*
X0235038D03*
X0237006D03*
X0250786D03*
X0252754D03*
X0244881D03*
X0246849D03*
X0260629D03*
X0254724D03*
X0262597D03*
X0256692D03*
X0225196Y0235868D03*
X0231101D03*
X0233069D03*
X0227165D03*
X0231101Y0251812D03*
X0233069D03*
X0280314Y0103817D03*
X0282283D03*
X0286221Y0087874D03*
X0288189D03*
X027441D03*
X0276378D03*
X0268503Y0103817D03*
X0270473D03*
X0258662Y0087874D03*
Y0103817D03*
X0264566Y0087874D03*
X0262598D03*
X027441Y0103817D03*
X0276378D03*
X0280314Y0087874D03*
X0282283D03*
X0268503D03*
X0270473D03*
X0262598Y0103817D03*
X0264566D03*
X0223229Y0087874D03*
X0242914D03*
X0237007D03*
X0235039D03*
X023307D03*
X0229134D03*
X0238977D03*
X0248818D03*
X0252755D03*
X0254725D03*
X0256693D03*
X0244882D03*
X024685D03*
X0225197D03*
X0227166D03*
X0256693Y0103817D03*
X0237007D03*
X0238977D03*
X0242914D03*
X024685D03*
X0248818D03*
X0244882D03*
X0229134D03*
X0227166D03*
X0225197D03*
X0223229D03*
X0235039D03*
X023307D03*
X0254725D03*
X0252755D03*
X0286221D03*
X0288189D03*
X0292126Y0087874D03*
Y0103817D03*
X0294094Y0087874D03*
Y0103817D03*
X0298031Y0087874D03*
Y0103817D03*
X0296062D03*
Y0087874D03*
X0290158Y0103817D03*
X0284251D03*
X0278346D03*
X0272441D03*
X0266535D03*
X026063D03*
X0250787D03*
X0240945D03*
X0231102D03*
X0290158Y0087874D03*
X0284251D03*
X0278346D03*
X0272441D03*
X0266535D03*
X026063D03*
X0250787D03*
X0240945D03*
X0231102D03*
X0221259D03*
X0264565Y0251812D03*
X0266534D03*
X0268502D03*
X0270472D03*
X027244D03*
X0274409D03*
X0276377D03*
X0278345D03*
X0280313D03*
X0282282D03*
X028425D03*
X028622D03*
X0288188D03*
X0290157D03*
X0292125D03*
X0294093D03*
X0296061D03*
X029803D03*
X0262597Y0235868D03*
X0266534D03*
X027244D03*
X0246849D03*
X0244881D03*
X0242913D03*
X0240944D03*
X0252754D03*
X0270472D03*
X0264565D03*
X0260629D03*
G54D48*
X0169689Y0126339D03*
X0357091D03*
X0169689Y0214331D03*
X0357091D03*
G54D49*
X0215654Y0243858D03*
Y0095827D03*
X0303646D03*
Y0243858D03*
G54D50*
X0349164Y0139823D03*
Y0137856D03*
Y0145729D03*
Y0147697D03*
Y0177225D03*
Y0149667D03*
Y0179193D03*
Y0189037D03*
Y0185099D03*
Y0187067D03*
Y0183131D03*
X0365107Y0187067D03*
Y0189037D03*
Y0192973D03*
X0349164Y0133918D03*
Y0135887D03*
X0365107Y0179193D03*
Y0177225D03*
Y0185099D03*
Y0183131D03*
Y0194941D03*
Y0198879D03*
Y0196911D03*
X0349164Y0198879D03*
Y0196911D03*
X0365107Y0169351D03*
X0349164Y0163445D03*
Y0167383D03*
Y0165415D03*
Y0169351D03*
X0365107Y0173289D03*
Y0175257D03*
Y0165415D03*
Y0157541D03*
Y0155571D03*
Y0167383D03*
Y0163445D03*
X0349164Y0192973D03*
Y0155571D03*
Y0200848D03*
Y0191005D03*
Y0181163D03*
Y0171319D03*
Y0161477D03*
Y0151635D03*
Y0141793D03*
X0365107Y0200848D03*
Y0191005D03*
Y0181163D03*
Y0171319D03*
Y0161477D03*
Y0151635D03*
Y0141793D03*
X0349164Y0194941D03*
X0365107Y0159509D03*
X0349164Y0153603D03*
X0365107Y0149667D03*
Y0147697D03*
Y0145729D03*
Y0143761D03*
Y0139823D03*
Y0137856D03*
Y0135887D03*
Y0133918D03*
X0349164Y0131949D03*
X0365107D03*
X0349164Y0173289D03*
Y0175257D03*
X0365107Y0153603D03*
X0349164Y0157541D03*
Y0159509D03*
Y0143761D03*
Y0208721D03*
Y0206752D03*
Y0204784D03*
Y0202816D03*
X0365107Y0208721D03*
Y0206752D03*
Y0204784D03*
Y0202816D03*
X0177617Y016345D03*
Y0161481D03*
Y0187072D03*
Y0202819D03*
Y0191008D03*
Y0183134D03*
Y0194946D03*
Y0173293D03*
Y0177229D03*
X0161672Y0192977D03*
Y0185103D03*
Y0191008D03*
Y0202819D03*
X0177617Y0200851D03*
Y0196915D03*
Y0145733D03*
Y0167386D03*
X0161672Y0187072D03*
Y0196915D03*
X0177617Y0192977D03*
Y0185103D03*
Y0181167D03*
Y0165419D03*
X0161672Y0200851D03*
X0177617Y017526D03*
Y0171324D03*
X0161672Y0194946D03*
X0177617Y0155576D03*
Y0157545D03*
X0161672Y0151638D03*
Y0145733D03*
Y0181167D03*
Y0183134D03*
X0177617Y0143764D03*
X0161672Y013589D03*
X0177617Y0133923D03*
X0161672Y0157545D03*
Y0143764D03*
Y0153607D03*
Y0155576D03*
Y0161481D03*
Y0173293D03*
Y0167386D03*
Y0137859D03*
Y0147702D03*
Y0141797D03*
Y017526D03*
X0177617Y013589D03*
X0161672Y0133923D03*
Y016345D03*
Y0177229D03*
X0177617Y0137859D03*
Y0131954D03*
Y0141797D03*
X0161672Y0131954D03*
X0177617Y0147702D03*
X0161672Y0171324D03*
Y0165419D03*
X0177617Y0151638D03*
X0161672Y0204788D03*
X0177617D03*
Y0139828D03*
Y0149671D03*
Y0159512D03*
Y0169355D03*
Y0179198D03*
Y0189041D03*
Y0198882D03*
X0161672Y0139828D03*
Y0149671D03*
Y0159512D03*
Y0169355D03*
Y0179198D03*
Y0189041D03*
Y0198882D03*
Y0208726D03*
X0177617D03*
Y0206756D03*
Y0153607D03*
X0161672Y0206756D03*
G54D51*
X0318848Y0285433D03*
Y0283465D03*
Y0281496D03*
Y0279528D03*
X0328789D03*
Y0281496D03*
Y0283465D03*
Y0285433D03*
G54D52*
X032185Y0278494D03*
X0323819D03*
X0325787D03*
Y0286467D03*
X0323819D03*
X032185D03*
G54D53*
X0357382Y0281201D03*
Y0278642D03*
X0349311D03*
Y0281201D03*
Y028376D03*
Y0286319D03*
X0357382D03*
Y028376D03*
G54D54*
X0301969Y0277298D03*
X0294488D03*
Y0285694D03*
X0298228D03*
G54D55*
X0301969Y0285694D03*
G54D56*
X0124984Y0419752D03*
Y0425461D03*
X0619291Y0282185D03*
Y0287894D03*
X0064484Y0425461D03*
Y0419752D03*
X0084651Y0425461D03*
Y0419752D03*
X0104818D03*
Y0425461D03*
G54D57*
X0355409Y0072606D03*
X0362496D03*
X0670028Y0142106D03*
X0662941D03*
X0670028Y0153106D03*
X0662941D03*
G54D58*
X0606484Y0238764D03*
Y0233449D03*
X0693984Y0187949D03*
Y0193264D03*
G54D59*
X0337598Y0269685D03*
Y0275197D03*
X021063Y0062992D03*
Y0068504D03*
X0286417Y0338386D03*
Y0332874D03*
X0270669Y0319685D03*
Y0314173D03*
X0285433Y027874D03*
Y0284252D03*
X05Y0289173D03*
Y0283661D03*
X0366142Y0295276D03*
Y0289764D03*
G54D60*
X0651984Y0201756D03*
Y0195457D03*
X0646984Y0230256D03*
Y0223957D03*
G54D61*
X0201969Y0062992D03*
Y0070079D03*
X0633484Y021815D03*
Y0211063D03*
X0665984Y0209563D03*
Y021665D03*
X0627559Y0282283D03*
Y028937D03*
X0636221Y0282283D03*
Y028937D03*
X0295276Y0332677D03*
Y0339764D03*
X0261811Y0321457D03*
Y031437D03*
G54D62*
X0684268Y0181606D03*
X0689701D03*
X0673661Y018189D03*
X0679095D03*
X0631142Y0246063D03*
X0636575D03*
X0139252Y0151575D03*
X0144685D03*
M02*